(kicad_sch (version 20230121) (generator eeschema)

  (paper "A3")

  (title_block
    (title "Data Center RDIMM DDR4 Tester")
    (date "2024-09-30")
    (rev "1.2.4")
    (company "Antmicro Ltd.")
    (comment 1 "www.antmicro.com")
    (comment 2 "Antmicro Ltd")
  )

  (junction (at 107.315 131.445) (diameter 0) (color 0 0 0 0)
  )
  (junction (at 114.935 100.965) (diameter 0) (color 0 0 0 0)
  )
  (junction (at 135.255 131.445) (diameter 0) (color 0 0 0 0)
  )
  (junction (at 219.71 109.22) (diameter 0) (color 0 0 0 0)
  )
  (junction (at 55.88 197.485) (diameter 0) (color 0 0 0 0)
  )
  (junction (at 78.74 166.37) (diameter 0) (color 0 0 0 0)
  )
  (junction (at 48.895 228.6) (diameter 0) (color 0 0 0 0)
  )
  (junction (at 121.285 131.445) (diameter 0) (color 0 0 0 0)
  )
  (junction (at 29.21 197.485) (diameter 0) (color 0 0 0 0)
  )
  (junction (at 93.98 63.5) (diameter 0) (color 0 0 0 0)
  )
  (junction (at 31.115 100.965) (diameter 0) (color 0 0 0 0)
  )
  (junction (at 37.465 131.445) (diameter 0) (color 0 0 0 0)
  )
  (junction (at 35.56 228.6) (diameter 0) (color 0 0 0 0)
  )
  (junction (at 255.27 109.22) (diameter 0) (color 0 0 0 0)
  )
  (junction (at 116.205 197.485) (diameter 0) (color 0 0 0 0)
  )
  (junction (at 81.915 228.6) (diameter 0) (color 0 0 0 0)
  )
  (junction (at 49.53 197.485) (diameter 0) (color 0 0 0 0)
  )
  (junction (at 269.875 109.22) (diameter 0) (color 0 0 0 0)
  )
  (junction (at 102.235 228.6) (diameter 0) (color 0 0 0 0)
  )
  (junction (at 320.675 70.485) (diameter 0) (color 0 0 0 0)
  )
  (junction (at 363.855 109.22) (diameter 0) (color 0 0 0 0)
  )
  (junction (at 128.27 63.5) (diameter 0) (color 0 0 0 0)
  )
  (junction (at 38.1 63.5) (diameter 0) (color 0 0 0 0)
  )
  (junction (at 107.95 100.965) (diameter 0) (color 0 0 0 0)
  )
  (junction (at 86.995 63.5) (diameter 0) (color 0 0 0 0)
  )
  (junction (at 100.965 63.5) (diameter 0) (color 0 0 0 0)
  )
  (junction (at 41.91 228.6) (diameter 0) (color 0 0 0 0)
  )
  (junction (at 266.065 88.265) (diameter 0) (color 0 0 0 0)
  )
  (junction (at 100.965 100.965) (diameter 0) (color 0 0 0 0)
  )
  (junction (at 266.065 62.865) (diameter 0) (color 0 0 0 0)
  )
  (junction (at 65.405 131.445) (diameter 0) (color 0 0 0 0)
  )
  (junction (at 31.115 63.5) (diameter 0) (color 0 0 0 0)
  )
  (junction (at 72.39 131.445) (diameter 0) (color 0 0 0 0)
  )
  (junction (at 58.42 131.445) (diameter 0) (color 0 0 0 0)
  )
  (junction (at 122.555 197.485) (diameter 0) (color 0 0 0 0)
  )
  (junction (at 114.3 131.445) (diameter 0) (color 0 0 0 0)
  )
  (junction (at 93.98 100.965) (diameter 0) (color 0 0 0 0)
  )
  (junction (at 102.87 197.485) (diameter 0) (color 0 0 0 0)
  )
  (junction (at 38.1 100.965) (diameter 0) (color 0 0 0 0)
  )
  (junction (at 114.3 63.5) (diameter 0) (color 0 0 0 0)
  )
  (junction (at 95.25 228.6) (diameter 0) (color 0 0 0 0)
  )
  (junction (at 149.225 63.5) (diameter 0) (color 0 0 0 0)
  )
  (junction (at 135.255 63.5) (diameter 0) (color 0 0 0 0)
  )
  (junction (at 55.245 228.6) (diameter 0) (color 0 0 0 0)
  )
  (junction (at 349.25 109.22) (diameter 0) (color 0 0 0 0)
  )
  (junction (at 28.575 228.6) (diameter 0) (color 0 0 0 0)
  )
  (junction (at 107.95 63.5) (diameter 0) (color 0 0 0 0)
  )
  (junction (at 50.8 166.37) (diameter 0) (color 0 0 0 0)
  )
  (junction (at 45.085 100.965) (diameter 0) (color 0 0 0 0)
  )
  (junction (at 121.285 63.5) (diameter 0) (color 0 0 0 0)
  )
  (junction (at 129.54 197.485) (diameter 0) (color 0 0 0 0)
  )
  (junction (at 170.18 63.5) (diameter 0) (color 0 0 0 0)
  )
  (junction (at 95.885 197.485) (diameter 0) (color 0 0 0 0)
  )
  (junction (at 89.535 197.485) (diameter 0) (color 0 0 0 0)
  )
  (junction (at 62.23 228.6) (diameter 0) (color 0 0 0 0)
  )
  (junction (at 64.77 166.37) (diameter 0) (color 0 0 0 0)
  )
  (junction (at 142.24 63.5) (diameter 0) (color 0 0 0 0)
  )
  (junction (at 62.865 197.485) (diameter 0) (color 0 0 0 0)
  )
  (junction (at 163.195 63.5) (diameter 0) (color 0 0 0 0)
  )
  (junction (at 93.345 131.445) (diameter 0) (color 0 0 0 0)
  )
  (junction (at 134.62 28.575) (diameter 0) (color 0 0 0 0)
  )
  (junction (at 59.055 100.965) (diameter 0) (color 0 0 0 0)
  )
  (junction (at 66.04 63.5) (diameter 0) (color 0 0 0 0)
  )
  (junction (at 51.435 131.445) (diameter 0) (color 0 0 0 0)
  )
  (junction (at 69.215 197.485) (diameter 0) (color 0 0 0 0)
  )
  (junction (at 277.495 109.22) (diameter 0) (color 0 0 0 0)
  )
  (junction (at 30.48 131.445) (diameter 0) (color 0 0 0 0)
  )
  (junction (at 36.195 197.485) (diameter 0) (color 0 0 0 0)
  )
  (junction (at 371.475 109.22) (diameter 0) (color 0 0 0 0)
  )
  (junction (at 43.815 166.37) (diameter 0) (color 0 0 0 0)
  )
  (junction (at 79.375 131.445) (diameter 0) (color 0 0 0 0)
  )
  (junction (at 59.055 63.5) (diameter 0) (color 0 0 0 0)
  )
  (junction (at 109.22 197.485) (diameter 0) (color 0 0 0 0)
  )
  (junction (at 88.9 228.6) (diameter 0) (color 0 0 0 0)
  )
  (junction (at 44.45 131.445) (diameter 0) (color 0 0 0 0)
  )
  (junction (at 73.025 100.965) (diameter 0) (color 0 0 0 0)
  )
  (junction (at 52.07 63.5) (diameter 0) (color 0 0 0 0)
  )
  (junction (at 143.51 100.965) (diameter 0) (color 0 0 0 0)
  )
  (junction (at 80.01 63.5) (diameter 0) (color 0 0 0 0)
  )
  (junction (at 356.235 109.22) (diameter 0) (color 0 0 0 0)
  )
  (junction (at 71.755 166.37) (diameter 0) (color 0 0 0 0)
  )
  (junction (at 75.565 228.6) (diameter 0) (color 0 0 0 0)
  )
  (junction (at 86.36 131.445) (diameter 0) (color 0 0 0 0)
  )
  (junction (at 156.21 63.5) (diameter 0) (color 0 0 0 0)
  )
  (junction (at 92.71 166.37) (diameter 0) (color 0 0 0 0)
  )
  (junction (at 52.07 100.965) (diameter 0) (color 0 0 0 0)
  )
  (junction (at 57.785 166.37) (diameter 0) (color 0 0 0 0)
  )
  (junction (at 262.89 109.22) (diameter 0) (color 0 0 0 0)
  )
  (junction (at 80.01 100.965) (diameter 0) (color 0 0 0 0)
  )
  (junction (at 73.025 63.5) (diameter 0) (color 0 0 0 0)
  )
  (junction (at 128.27 131.445) (diameter 0) (color 0 0 0 0)
  )
  (junction (at 135.89 197.485) (diameter 0) (color 0 0 0 0)
  )
  (junction (at 86.995 100.965) (diameter 0) (color 0 0 0 0)
  )
  (junction (at 45.085 63.5) (diameter 0) (color 0 0 0 0)
  )
  (junction (at 326.39 109.22) (diameter 0) (color 0 0 0 0)
  )
  (junction (at 29.845 166.37) (diameter 0) (color 0 0 0 0)
  )
  (junction (at 285.115 109.22) (diameter 0) (color 0 0 0 0)
  )
  (junction (at 68.58 228.6) (diameter 0) (color 0 0 0 0)
  )
  (junction (at 334.01 109.22) (diameter 0) (color 0 0 0 0)
  )
  (junction (at 36.83 166.37) (diameter 0) (color 0 0 0 0)
  )
  (junction (at 82.55 197.485) (diameter 0) (color 0 0 0 0)
  )
  (junction (at 42.545 197.485) (diameter 0) (color 0 0 0 0)
  )
  (junction (at 85.725 166.37) (diameter 0) (color 0 0 0 0)
  )
  (junction (at 100.33 131.445) (diameter 0) (color 0 0 0 0)
  )
  (junction (at 341.63 109.22) (diameter 0) (color 0 0 0 0)
  )
  (junction (at 66.04 100.965) (diameter 0) (color 0 0 0 0)
  )
  (junction (at 76.2 197.485) (diameter 0) (color 0 0 0 0)
  )
  (junction (at 318.77 109.22) (diameter 0) (color 0 0 0 0)
  )

  (wire (pts (xy 316.23 70.485) (xy 320.675 70.485))
    (stroke (width 0) (type default))
  )
  (wire (pts (xy 81.915 228.6) (xy 88.9 228.6))
    (stroke (width 0) (type default))
  )
  (wire (pts (xy 55.88 201.295) (xy 55.88 197.485))
    (stroke (width 0) (type default))
  )
  (wire (pts (xy 36.83 170.18) (xy 36.83 166.37))
    (stroke (width 0) (type default))
  )
  (wire (pts (xy 75.565 228.6) (xy 81.915 228.6))
    (stroke (width 0) (type default))
  )
  (wire (pts (xy 252.095 62.865) (xy 266.065 62.865))
    (stroke (width 0) (type default))
  )
  (wire (pts (xy 29.845 166.37) (xy 36.83 166.37))
    (stroke (width 0) (type default))
  )
  (wire (pts (xy 43.815 166.37) (xy 50.8 166.37))
    (stroke (width 0) (type default))
  )
  (wire (pts (xy 85.725 166.37) (xy 92.71 166.37))
    (stroke (width 0) (type default))
  )
  (wire (pts (xy 107.315 131.445) (xy 100.33 131.445))
    (stroke (width 0) (type default))
  )
  (wire (pts (xy 121.285 135.255) (xy 121.285 131.445))
    (stroke (width 0) (type default))
  )
  (wire (pts (xy 170.18 63.5) (xy 163.195 63.5))
    (stroke (width 0) (type default))
  )
  (wire (pts (xy 86.36 131.445) (xy 79.375 131.445))
    (stroke (width 0) (type default))
  )
  (wire (pts (xy 266.065 88.265) (xy 268.605 88.265))
    (stroke (width 0) (type default))
  )
  (wire (pts (xy 135.89 201.295) (xy 135.89 197.485))
    (stroke (width 0) (type default))
  )
  (wire (pts (xy 80.01 63.5) (xy 80.01 66.04))
    (stroke (width 0) (type default))
  )
  (wire (pts (xy 35.56 232.41) (xy 35.56 228.6))
    (stroke (width 0) (type default))
  )
  (wire (pts (xy 43.815 170.18) (xy 43.815 166.37))
    (stroke (width 0) (type default))
  )
  (wire (pts (xy 100.965 100.965) (xy 107.95 100.965))
    (stroke (width 0) (type default))
  )
  (wire (pts (xy 121.92 100.965) (xy 121.92 104.775))
    (stroke (width 0) (type default))
  )
  (wire (pts (xy 109.22 197.485) (xy 116.205 197.485))
    (stroke (width 0) (type default))
  )
  (wire (pts (xy 151.765 104.775) (xy 151.765 100.965))
    (stroke (width 0) (type default))
  )
  (wire (pts (xy 52.07 63.5) (xy 52.07 66.04))
    (stroke (width 0) (type default))
  )
  (wire (pts (xy 59.055 63.5) (xy 59.055 66.04))
    (stroke (width 0) (type default))
  )
  (wire (pts (xy 79.375 131.445) (xy 72.39 131.445))
    (stroke (width 0) (type default))
  )
  (wire (pts (xy 252.095 57.785) (xy 268.605 57.785))
    (stroke (width 0) (type default))
  )
  (wire (pts (xy 334.01 111.125) (xy 334.01 109.22))
    (stroke (width 0) (type default))
  )
  (wire (pts (xy 93.98 100.965) (xy 100.965 100.965))
    (stroke (width 0) (type default))
  )
  (wire (pts (xy 59.055 100.965) (xy 66.04 100.965))
    (stroke (width 0) (type default))
  )
  (wire (pts (xy 128.27 131.445) (xy 121.285 131.445))
    (stroke (width 0) (type default))
  )
  (wire (pts (xy 24.765 228.6) (xy 28.575 228.6))
    (stroke (width 0) (type default))
  )
  (wire (pts (xy 76.2 197.485) (xy 82.55 197.485))
    (stroke (width 0) (type default))
  )
  (wire (pts (xy 255.27 109.22) (xy 255.27 111.125))
    (stroke (width 0) (type default))
  )
  (wire (pts (xy 66.04 63.5) (xy 66.04 66.04))
    (stroke (width 0) (type default))
  )
  (wire (pts (xy 219.71 109.22) (xy 229.87 109.22))
    (stroke (width 0) (type default))
  )
  (wire (pts (xy 93.345 135.255) (xy 93.345 131.445))
    (stroke (width 0) (type default))
  )
  (wire (pts (xy 114.3 63.5) (xy 107.95 63.5))
    (stroke (width 0) (type default))
  )
  (wire (pts (xy 85.725 170.18) (xy 85.725 166.37))
    (stroke (width 0) (type default))
  )
  (wire (pts (xy 66.04 63.5) (xy 59.055 63.5))
    (stroke (width 0) (type default))
  )
  (wire (pts (xy 219.71 109.22) (xy 219.71 111.125))
    (stroke (width 0) (type default))
  )
  (wire (pts (xy 27.94 63.5) (xy 31.115 63.5))
    (stroke (width 0) (type default))
  )
  (wire (pts (xy 89.535 201.295) (xy 89.535 197.485))
    (stroke (width 0) (type default))
  )
  (wire (pts (xy 135.255 135.255) (xy 135.255 131.445))
    (stroke (width 0) (type default))
  )
  (wire (pts (xy 102.87 197.485) (xy 109.22 197.485))
    (stroke (width 0) (type default))
  )
  (wire (pts (xy 28.575 228.6) (xy 35.56 228.6))
    (stroke (width 0) (type default))
  )
  (wire (pts (xy 129.54 201.295) (xy 129.54 197.485))
    (stroke (width 0) (type default))
  )
  (wire (pts (xy 36.195 201.295) (xy 36.195 197.485))
    (stroke (width 0) (type default))
  )
  (wire (pts (xy 268.605 73.025) (xy 266.065 73.025))
    (stroke (width 0) (type default))
  )
  (wire (pts (xy 81.915 232.41) (xy 81.915 228.6))
    (stroke (width 0) (type default))
  )
  (wire (pts (xy 38.1 100.965) (xy 45.085 100.965))
    (stroke (width 0) (type default))
  )
  (wire (pts (xy 62.865 197.485) (xy 69.215 197.485))
    (stroke (width 0) (type default))
  )
  (wire (pts (xy 170.18 63.5) (xy 170.18 66.04))
    (stroke (width 0) (type default))
  )
  (wire (pts (xy 252.095 70.485) (xy 268.605 70.485))
    (stroke (width 0) (type default))
  )
  (wire (pts (xy 142.24 63.5) (xy 142.24 66.04))
    (stroke (width 0) (type default))
  )
  (wire (pts (xy 107.95 63.5) (xy 100.965 63.5))
    (stroke (width 0) (type default))
  )
  (wire (pts (xy 28.575 232.41) (xy 28.575 228.6))
    (stroke (width 0) (type default))
  )
  (wire (pts (xy 100.33 135.255) (xy 100.33 131.445))
    (stroke (width 0) (type default))
  )
  (wire (pts (xy 107.95 100.965) (xy 114.935 100.965))
    (stroke (width 0) (type default))
  )
  (wire (pts (xy 320.675 70.485) (xy 320.675 71.755))
    (stroke (width 0) (type default))
  )
  (wire (pts (xy 313.055 73.025) (xy 316.23 73.025))
    (stroke (width 0) (type default))
  )
  (wire (pts (xy 268.605 65.405) (xy 266.065 65.405))
    (stroke (width 0) (type default))
  )
  (wire (pts (xy 163.195 63.5) (xy 156.21 63.5))
    (stroke (width 0) (type default))
  )
  (wire (pts (xy 107.95 100.965) (xy 107.95 104.775))
    (stroke (width 0) (type default))
  )
  (wire (pts (xy 51.435 131.445) (xy 44.45 131.445))
    (stroke (width 0) (type default))
  )
  (wire (pts (xy 72.39 131.445) (xy 65.405 131.445))
    (stroke (width 0) (type default))
  )
  (wire (pts (xy 285.115 109.22) (xy 285.115 111.125))
    (stroke (width 0) (type default))
  )
  (wire (pts (xy 277.495 109.22) (xy 285.115 109.22))
    (stroke (width 0) (type default))
  )
  (polyline (pts (xy 150.495 45.085) (xy 120.65 45.085))
    (stroke (width 0) (type default))
  )

  (wire (pts (xy 114.3 131.445) (xy 107.315 131.445))
    (stroke (width 0) (type default))
  )
  (wire (pts (xy 65.405 131.445) (xy 58.42 131.445))
    (stroke (width 0) (type default))
  )
  (wire (pts (xy 326.39 109.22) (xy 334.01 109.22))
    (stroke (width 0) (type default))
  )
  (wire (pts (xy 292.1 109.22) (xy 292.1 111.125))
    (stroke (width 0) (type default))
  )
  (wire (pts (xy 45.085 100.965) (xy 45.085 104.775))
    (stroke (width 0) (type default))
  )
  (wire (pts (xy 318.77 109.22) (xy 318.77 111.125))
    (stroke (width 0) (type default))
  )
  (wire (pts (xy 59.055 100.965) (xy 59.055 104.775))
    (stroke (width 0) (type default))
  )
  (wire (pts (xy 156.21 63.5) (xy 156.21 66.04))
    (stroke (width 0) (type default))
  )
  (wire (pts (xy 64.77 166.37) (xy 71.755 166.37))
    (stroke (width 0) (type default))
  )
  (wire (pts (xy 285.115 109.22) (xy 292.1 109.22))
    (stroke (width 0) (type default))
  )
  (wire (pts (xy 102.235 228.6) (xy 108.585 228.6))
    (stroke (width 0) (type default))
  )
  (polyline (pts (xy 128.905 117.475) (xy 128.905 96.52))
    (stroke (width 0) (type default))
  )

  (wire (pts (xy 26.67 166.37) (xy 29.845 166.37))
    (stroke (width 0) (type default))
  )
  (wire (pts (xy 108.585 232.41) (xy 108.585 228.6))
    (stroke (width 0) (type default))
  )
  (wire (pts (xy 93.98 100.965) (xy 93.98 104.775))
    (stroke (width 0) (type default))
  )
  (wire (pts (xy 26.67 131.445) (xy 30.48 131.445))
    (stroke (width 0) (type default))
  )
  (wire (pts (xy 363.855 109.22) (xy 371.475 109.22))
    (stroke (width 0) (type default))
  )
  (wire (pts (xy 316.23 75.565) (xy 316.23 78.105))
    (stroke (width 0) (type default))
  )
  (wire (pts (xy 135.89 197.485) (xy 142.875 197.485))
    (stroke (width 0) (type default))
  )
  (wire (pts (xy 320.675 70.485) (xy 329.565 70.485))
    (stroke (width 0) (type default))
  )
  (wire (pts (xy 134.62 28.575) (xy 142.875 28.575))
    (stroke (width 0) (type default))
  )
  (wire (pts (xy 100.965 63.5) (xy 93.98 63.5))
    (stroke (width 0) (type default))
  )
  (wire (pts (xy 128.27 135.255) (xy 128.27 131.445))
    (stroke (width 0) (type default))
  )
  (wire (pts (xy 116.205 197.485) (xy 122.555 197.485))
    (stroke (width 0) (type default))
  )
  (wire (pts (xy 135.255 63.5) (xy 135.255 66.04))
    (stroke (width 0) (type default))
  )
  (wire (pts (xy 135.255 63.5) (xy 128.27 63.5))
    (stroke (width 0) (type default))
  )
  (wire (pts (xy 122.555 197.485) (xy 129.54 197.485))
    (stroke (width 0) (type default))
  )
  (wire (pts (xy 356.235 111.125) (xy 356.235 109.22))
    (stroke (width 0) (type default))
  )
  (wire (pts (xy 142.24 135.255) (xy 142.24 131.445))
    (stroke (width 0) (type default))
  )
  (wire (pts (xy 86.995 100.965) (xy 93.98 100.965))
    (stroke (width 0) (type default))
  )
  (wire (pts (xy 89.535 197.485) (xy 95.885 197.485))
    (stroke (width 0) (type default))
  )
  (wire (pts (xy 45.085 63.5) (xy 45.085 66.04))
    (stroke (width 0) (type default))
  )
  (wire (pts (xy 143.51 100.965) (xy 151.765 100.965))
    (stroke (width 0) (type default))
  )
  (wire (pts (xy 92.71 166.37) (xy 99.695 166.37))
    (stroke (width 0) (type default))
  )
  (wire (pts (xy 313.055 57.785) (xy 329.565 57.785))
    (stroke (width 0) (type default))
  )
  (wire (pts (xy 31.115 63.5) (xy 31.115 66.04))
    (stroke (width 0) (type default))
  )
  (wire (pts (xy 93.98 63.5) (xy 86.995 63.5))
    (stroke (width 0) (type default))
  )
  (wire (pts (xy 341.63 109.22) (xy 349.25 109.22))
    (stroke (width 0) (type default))
  )
  (wire (pts (xy 41.91 228.6) (xy 48.895 228.6))
    (stroke (width 0) (type default))
  )
  (wire (pts (xy 51.435 135.255) (xy 51.435 131.445))
    (stroke (width 0) (type default))
  )
  (wire (pts (xy 73.025 100.965) (xy 73.025 104.775))
    (stroke (width 0) (type default))
  )
  (wire (pts (xy 76.2 201.295) (xy 76.2 197.485))
    (stroke (width 0) (type default))
  )
  (wire (pts (xy 78.74 170.18) (xy 78.74 166.37))
    (stroke (width 0) (type default))
  )
  (wire (pts (xy 156.21 63.5) (xy 149.225 63.5))
    (stroke (width 0) (type default))
  )
  (wire (pts (xy 266.065 88.265) (xy 266.065 90.17))
    (stroke (width 0) (type default))
  )
  (wire (pts (xy 55.245 228.6) (xy 62.23 228.6))
    (stroke (width 0) (type default))
  )
  (wire (pts (xy 62.865 201.295) (xy 62.865 197.485))
    (stroke (width 0) (type default))
  )
  (wire (pts (xy 320.675 78.105) (xy 320.675 76.835))
    (stroke (width 0) (type default))
  )
  (wire (pts (xy 99.695 170.18) (xy 99.695 166.37))
    (stroke (width 0) (type default))
  )
  (wire (pts (xy 217.805 109.22) (xy 219.71 109.22))
    (stroke (width 0) (type default))
  )
  (wire (pts (xy 66.04 100.965) (xy 73.025 100.965))
    (stroke (width 0) (type default))
  )
  (wire (pts (xy 72.39 135.255) (xy 72.39 131.445))
    (stroke (width 0) (type default))
  )
  (wire (pts (xy 80.01 100.965) (xy 86.995 100.965))
    (stroke (width 0) (type default))
  )
  (wire (pts (xy 38.1 63.5) (xy 38.1 66.04))
    (stroke (width 0) (type default))
  )
  (wire (pts (xy 266.065 65.405) (xy 266.065 62.865))
    (stroke (width 0) (type default))
  )
  (wire (pts (xy 114.935 100.965) (xy 114.935 104.775))
    (stroke (width 0) (type default))
  )
  (wire (pts (xy 100.965 100.965) (xy 100.965 104.775))
    (stroke (width 0) (type default))
  )
  (wire (pts (xy 269.875 109.22) (xy 277.495 109.22))
    (stroke (width 0) (type default))
  )
  (wire (pts (xy 86.36 135.255) (xy 86.36 131.445))
    (stroke (width 0) (type default))
  )
  (wire (pts (xy 50.8 166.37) (xy 57.785 166.37))
    (stroke (width 0) (type default))
  )
  (wire (pts (xy 109.22 201.295) (xy 109.22 197.485))
    (stroke (width 0) (type default))
  )
  (wire (pts (xy 45.085 63.5) (xy 38.1 63.5))
    (stroke (width 0) (type default))
  )
  (wire (pts (xy 142.875 31.75) (xy 142.875 28.575))
    (stroke (width 0) (type default))
  )
  (wire (pts (xy 95.25 232.41) (xy 95.25 228.6))
    (stroke (width 0) (type default))
  )
  (wire (pts (xy 69.215 201.295) (xy 69.215 197.485))
    (stroke (width 0) (type default))
  )
  (wire (pts (xy 114.3 63.5) (xy 114.3 66.04))
    (stroke (width 0) (type default))
  )
  (wire (pts (xy 49.53 201.295) (xy 49.53 197.485))
    (stroke (width 0) (type default))
  )
  (wire (pts (xy 73.025 63.5) (xy 73.025 66.04))
    (stroke (width 0) (type default))
  )
  (wire (pts (xy 52.07 100.965) (xy 59.055 100.965))
    (stroke (width 0) (type default))
  )
  (wire (pts (xy 55.88 197.485) (xy 62.865 197.485))
    (stroke (width 0) (type default))
  )
  (wire (pts (xy 66.04 100.965) (xy 66.04 104.775))
    (stroke (width 0) (type default))
  )
  (wire (pts (xy 116.205 201.295) (xy 116.205 197.485))
    (stroke (width 0) (type default))
  )
  (wire (pts (xy 102.235 232.41) (xy 102.235 228.6))
    (stroke (width 0) (type default))
  )
  (wire (pts (xy 379.095 109.22) (xy 379.095 111.125))
    (stroke (width 0) (type default))
  )
  (wire (pts (xy 341.63 109.22) (xy 341.63 111.125))
    (stroke (width 0) (type default))
  )
  (polyline (pts (xy 128.905 96.52) (xy 159.385 96.52))
    (stroke (width 0) (type default))
  )
  (polyline (pts (xy 150.495 23.495) (xy 150.495 45.085))
    (stroke (width 0) (type default))
  )

  (wire (pts (xy 59.055 63.5) (xy 52.07 63.5))
    (stroke (width 0) (type default))
  )
  (wire (pts (xy 37.465 135.255) (xy 37.465 131.445))
    (stroke (width 0) (type default))
  )
  (wire (pts (xy 100.33 131.445) (xy 93.345 131.445))
    (stroke (width 0) (type default))
  )
  (wire (pts (xy 142.24 63.5) (xy 135.255 63.5))
    (stroke (width 0) (type default))
  )
  (wire (pts (xy 80.01 100.965) (xy 80.01 104.775))
    (stroke (width 0) (type default))
  )
  (wire (pts (xy 58.42 135.255) (xy 58.42 131.445))
    (stroke (width 0) (type default))
  )
  (polyline (pts (xy 159.385 117.475) (xy 128.905 117.475))
    (stroke (width 0) (type default))
  )

  (wire (pts (xy 363.855 109.22) (xy 363.855 111.125))
    (stroke (width 0) (type default))
  )
  (wire (pts (xy 71.755 166.37) (xy 78.74 166.37))
    (stroke (width 0) (type default))
  )
  (wire (pts (xy 100.965 63.5) (xy 100.965 66.04))
    (stroke (width 0) (type default))
  )
  (wire (pts (xy 316.23 73.025) (xy 316.23 70.485))
    (stroke (width 0) (type default))
  )
  (wire (pts (xy 318.77 109.22) (xy 326.39 109.22))
    (stroke (width 0) (type default))
  )
  (wire (pts (xy 86.995 100.965) (xy 86.995 104.775))
    (stroke (width 0) (type default))
  )
  (wire (pts (xy 371.475 109.22) (xy 371.475 111.125))
    (stroke (width 0) (type default))
  )
  (wire (pts (xy 82.55 197.485) (xy 89.535 197.485))
    (stroke (width 0) (type default))
  )
  (wire (pts (xy 79.375 135.255) (xy 79.375 131.445))
    (stroke (width 0) (type default))
  )
  (wire (pts (xy 93.98 63.5) (xy 93.98 66.04))
    (stroke (width 0) (type default))
  )
  (wire (pts (xy 349.25 109.22) (xy 349.25 111.125))
    (stroke (width 0) (type default))
  )
  (wire (pts (xy 95.25 228.6) (xy 102.235 228.6))
    (stroke (width 0) (type default))
  )
  (wire (pts (xy 114.935 100.965) (xy 121.92 100.965))
    (stroke (width 0) (type default))
  )
  (wire (pts (xy 31.115 100.965) (xy 38.1 100.965))
    (stroke (width 0) (type default))
  )
  (wire (pts (xy 29.21 201.295) (xy 29.21 197.485))
    (stroke (width 0) (type default))
  )
  (wire (pts (xy 128.27 63.5) (xy 128.27 66.04))
    (stroke (width 0) (type default))
  )
  (wire (pts (xy 82.55 201.295) (xy 82.55 197.485))
    (stroke (width 0) (type default))
  )
  (wire (pts (xy 139.7 100.965) (xy 143.51 100.965))
    (stroke (width 0) (type default))
  )
  (wire (pts (xy 36.195 197.485) (xy 42.545 197.485))
    (stroke (width 0) (type default))
  )
  (wire (pts (xy 73.025 100.965) (xy 80.01 100.965))
    (stroke (width 0) (type default))
  )
  (wire (pts (xy 45.085 100.965) (xy 52.07 100.965))
    (stroke (width 0) (type default))
  )
  (wire (pts (xy 29.845 170.18) (xy 29.845 166.37))
    (stroke (width 0) (type default))
  )
  (wire (pts (xy 129.54 197.485) (xy 135.89 197.485))
    (stroke (width 0) (type default))
  )
  (polyline (pts (xy 120.65 23.495) (xy 150.495 23.495))
    (stroke (width 0) (type default))
  )

  (wire (pts (xy 313.055 67.945) (xy 329.565 67.945))
    (stroke (width 0) (type default))
  )
  (wire (pts (xy 68.58 232.41) (xy 68.58 228.6))
    (stroke (width 0) (type default))
  )
  (wire (pts (xy 57.785 166.37) (xy 64.77 166.37))
    (stroke (width 0) (type default))
  )
  (wire (pts (xy 88.9 228.6) (xy 95.25 228.6))
    (stroke (width 0) (type default))
  )
  (wire (pts (xy 27.94 100.965) (xy 31.115 100.965))
    (stroke (width 0) (type default))
  )
  (wire (pts (xy 262.89 109.22) (xy 269.875 109.22))
    (stroke (width 0) (type default))
  )
  (wire (pts (xy 149.225 63.5) (xy 142.24 63.5))
    (stroke (width 0) (type default))
  )
  (wire (pts (xy 42.545 201.295) (xy 42.545 197.485))
    (stroke (width 0) (type default))
  )
  (wire (pts (xy 114.3 135.255) (xy 114.3 131.445))
    (stroke (width 0) (type default))
  )
  (wire (pts (xy 62.23 228.6) (xy 68.58 228.6))
    (stroke (width 0) (type default))
  )
  (wire (pts (xy 52.07 100.965) (xy 52.07 104.775))
    (stroke (width 0) (type default))
  )
  (wire (pts (xy 71.755 170.18) (xy 71.755 166.37))
    (stroke (width 0) (type default))
  )
  (wire (pts (xy 65.405 135.255) (xy 65.405 131.445))
    (stroke (width 0) (type default))
  )
  (wire (pts (xy 64.77 170.18) (xy 64.77 166.37))
    (stroke (width 0) (type default))
  )
  (wire (pts (xy 36.83 166.37) (xy 43.815 166.37))
    (stroke (width 0) (type default))
  )
  (wire (pts (xy 93.345 131.445) (xy 86.36 131.445))
    (stroke (width 0) (type default))
  )
  (wire (pts (xy 349.25 109.22) (xy 356.235 109.22))
    (stroke (width 0) (type default))
  )
  (wire (pts (xy 266.065 73.025) (xy 266.065 88.265))
    (stroke (width 0) (type default))
  )
  (wire (pts (xy 316.23 78.105) (xy 320.675 78.105))
    (stroke (width 0) (type default))
  )
  (wire (pts (xy 252.095 78.105) (xy 268.605 78.105))
    (stroke (width 0) (type default))
  )
  (polyline (pts (xy 191.135 12.7) (xy 191.135 283.845))
    (stroke (width 0) (type default))
  )
  (polyline (pts (xy 159.385 96.52) (xy 159.385 117.475))
    (stroke (width 0) (type default))
  )

  (wire (pts (xy 177.165 63.5) (xy 170.18 63.5))
    (stroke (width 0) (type default))
  )
  (wire (pts (xy 107.315 135.255) (xy 107.315 131.445))
    (stroke (width 0) (type default))
  )
  (wire (pts (xy 41.91 232.41) (xy 41.91 228.6))
    (stroke (width 0) (type default))
  )
  (wire (pts (xy 48.895 232.41) (xy 48.895 228.6))
    (stroke (width 0) (type default))
  )
  (wire (pts (xy 86.995 63.5) (xy 86.995 66.04))
    (stroke (width 0) (type default))
  )
  (wire (pts (xy 163.195 63.5) (xy 163.195 66.04))
    (stroke (width 0) (type default))
  )
  (wire (pts (xy 35.56 228.6) (xy 41.91 228.6))
    (stroke (width 0) (type default))
  )
  (wire (pts (xy 334.01 109.22) (xy 341.63 109.22))
    (stroke (width 0) (type default))
  )
  (wire (pts (xy 102.87 201.295) (xy 102.87 197.485))
    (stroke (width 0) (type default))
  )
  (wire (pts (xy 88.9 232.41) (xy 88.9 228.6))
    (stroke (width 0) (type default))
  )
  (wire (pts (xy 128.27 63.5) (xy 121.285 63.5))
    (stroke (width 0) (type default))
  )
  (wire (pts (xy 44.45 135.255) (xy 44.45 131.445))
    (stroke (width 0) (type default))
  )
  (wire (pts (xy 121.285 131.445) (xy 114.3 131.445))
    (stroke (width 0) (type default))
  )
  (wire (pts (xy 75.565 232.41) (xy 75.565 228.6))
    (stroke (width 0) (type default))
  )
  (wire (pts (xy 38.1 100.965) (xy 38.1 104.775))
    (stroke (width 0) (type default))
  )
  (wire (pts (xy 86.995 63.5) (xy 80.01 63.5))
    (stroke (width 0) (type default))
  )
  (wire (pts (xy 69.215 197.485) (xy 76.2 197.485))
    (stroke (width 0) (type default))
  )
  (wire (pts (xy 42.545 197.485) (xy 49.53 197.485))
    (stroke (width 0) (type default))
  )
  (wire (pts (xy 229.87 109.22) (xy 229.87 111.125))
    (stroke (width 0) (type default))
  )
  (wire (pts (xy 326.39 109.22) (xy 326.39 111.125))
    (stroke (width 0) (type default))
  )
  (wire (pts (xy 315.595 109.22) (xy 318.77 109.22))
    (stroke (width 0) (type default))
  )
  (wire (pts (xy 356.235 109.22) (xy 363.855 109.22))
    (stroke (width 0) (type default))
  )
  (wire (pts (xy 277.495 109.22) (xy 277.495 111.125))
    (stroke (width 0) (type default))
  )
  (wire (pts (xy 266.065 62.865) (xy 268.605 62.865))
    (stroke (width 0) (type default))
  )
  (wire (pts (xy 55.245 232.41) (xy 55.245 228.6))
    (stroke (width 0) (type default))
  )
  (wire (pts (xy 25.4 197.485) (xy 29.21 197.485))
    (stroke (width 0) (type default))
  )
  (wire (pts (xy 38.1 63.5) (xy 31.115 63.5))
    (stroke (width 0) (type default))
  )
  (wire (pts (xy 313.055 75.565) (xy 316.23 75.565))
    (stroke (width 0) (type default))
  )
  (wire (pts (xy 135.255 131.445) (xy 128.27 131.445))
    (stroke (width 0) (type default))
  )
  (wire (pts (xy 62.23 232.41) (xy 62.23 228.6))
    (stroke (width 0) (type default))
  )
  (polyline (pts (xy 191.135 283.845) (xy 191.77 283.845))
    (stroke (width 0) (type default))
  )

  (wire (pts (xy 269.875 111.125) (xy 269.875 109.22))
    (stroke (width 0) (type default))
  )
  (wire (pts (xy 52.07 63.5) (xy 45.085 63.5))
    (stroke (width 0) (type default))
  )
  (polyline (pts (xy 120.65 45.085) (xy 120.65 23.495))
    (stroke (width 0) (type default))
  )

  (wire (pts (xy 50.8 170.18) (xy 50.8 166.37))
    (stroke (width 0) (type default))
  )
  (wire (pts (xy 57.785 170.18) (xy 57.785 166.37))
    (stroke (width 0) (type default))
  )
  (wire (pts (xy 121.285 63.5) (xy 121.285 66.04))
    (stroke (width 0) (type default))
  )
  (wire (pts (xy 107.95 63.5) (xy 107.95 66.04))
    (stroke (width 0) (type default))
  )
  (wire (pts (xy 252.095 83.185) (xy 268.605 83.185))
    (stroke (width 0) (type default))
  )
  (wire (pts (xy 29.21 197.485) (xy 36.195 197.485))
    (stroke (width 0) (type default))
  )
  (wire (pts (xy 44.45 131.445) (xy 37.465 131.445))
    (stroke (width 0) (type default))
  )
  (wire (pts (xy 48.895 228.6) (xy 55.245 228.6))
    (stroke (width 0) (type default))
  )
  (wire (pts (xy 68.58 228.6) (xy 75.565 228.6))
    (stroke (width 0) (type default))
  )
  (wire (pts (xy 92.71 170.18) (xy 92.71 166.37))
    (stroke (width 0) (type default))
  )
  (wire (pts (xy 132.08 28.575) (xy 134.62 28.575))
    (stroke (width 0) (type default))
  )
  (wire (pts (xy 134.62 31.75) (xy 134.62 28.575))
    (stroke (width 0) (type default))
  )
  (wire (pts (xy 143.51 104.775) (xy 143.51 100.965))
    (stroke (width 0) (type default))
  )
  (wire (pts (xy 30.48 135.255) (xy 30.48 131.445))
    (stroke (width 0) (type default))
  )
  (wire (pts (xy 142.24 131.445) (xy 135.255 131.445))
    (stroke (width 0) (type default))
  )
  (wire (pts (xy 58.42 131.445) (xy 51.435 131.445))
    (stroke (width 0) (type default))
  )
  (wire (pts (xy 142.875 201.295) (xy 142.875 197.485))
    (stroke (width 0) (type default))
  )
  (wire (pts (xy 95.885 197.485) (xy 102.87 197.485))
    (stroke (width 0) (type default))
  )
  (wire (pts (xy 122.555 201.295) (xy 122.555 197.485))
    (stroke (width 0) (type default))
  )
  (wire (pts (xy 31.115 100.965) (xy 31.115 104.775))
    (stroke (width 0) (type default))
  )
  (wire (pts (xy 78.74 166.37) (xy 85.725 166.37))
    (stroke (width 0) (type default))
  )
  (wire (pts (xy 252.095 109.22) (xy 255.27 109.22))
    (stroke (width 0) (type default))
  )
  (wire (pts (xy 37.465 131.445) (xy 30.48 131.445))
    (stroke (width 0) (type default))
  )
  (wire (pts (xy 95.885 201.295) (xy 95.885 197.485))
    (stroke (width 0) (type default))
  )
  (wire (pts (xy 73.025 63.5) (xy 66.04 63.5))
    (stroke (width 0) (type default))
  )
  (wire (pts (xy 149.225 63.5) (xy 149.225 66.04))
    (stroke (width 0) (type default))
  )
  (wire (pts (xy 262.89 109.22) (xy 262.89 111.125))
    (stroke (width 0) (type default))
  )
  (wire (pts (xy 255.27 109.22) (xy 262.89 109.22))
    (stroke (width 0) (type default))
  )
  (wire (pts (xy 371.475 109.22) (xy 379.095 109.22))
    (stroke (width 0) (type default))
  )
  (wire (pts (xy 49.53 197.485) (xy 55.88 197.485))
    (stroke (width 0) (type default))
  )
  (wire (pts (xy 329.565 62.865) (xy 313.055 62.865))
    (stroke (width 0) (type default))
  )
  (wire (pts (xy 177.165 66.04) (xy 177.165 63.5))
    (stroke (width 0) (type default))
  )
  (wire (pts (xy 121.285 63.5) (xy 114.3 63.5))
    (stroke (width 0) (type default))
  )
  (wire (pts (xy 80.01 63.5) (xy 73.025 63.5))
    (stroke (width 0) (type default))
  )

  (text "Decoupling referenced from 7 Series FPGAs\nPCB Design Guide UG483 \nTODO: verify!"
    (at 271.145 43.815 0)
    (effects (font (size 1.27 1.27)) (justify left bottom))
  )
  (text "Added capacitors coresponding to PCB Design Guide UG483"
    (at 48.26 44.45 0)
    (effects (font (size 1.27 1.27)) (justify left bottom))
  )
  (text "POWER RAILS" (at 278.765 37.465 0)
    (effects (font (size 2.4892 2.4892) (thickness 0.4978) bold) (justify left bottom))
  )
  (text "VCCAUX max: 2.0V" (at 241.935 61.595 0)
    (effects (font (size 1.27 1.27)) (justify left bottom))
  )
  (text "VCCBRAM max: 1.1V" (at 241.935 81.915 0)
    (effects (font (size 1.27 1.27)) (justify left bottom))
  )
  (text "VCCINT max: 1.1V" (at 241.935 56.515 0)
    (effects (font (size 1.27 1.27)) (justify left bottom))
  )
  (text "Trace length from the resistor pins to the\nFPGA pins MGTRREF and MGTAVTTRCAL\nmust be equal in length."
    (at 310.515 83.82 0)
    (effects (font (size 1 1)) (justify left bottom))
  )
  (text "VCCBATT max: 2.0V" (at 241.935 76.835 0)
    (effects (font (size 1.27 1.27)) (justify left bottom))
  )
  (text "VCCADC max: 2.0V" (at 241.935 69.215 0)
    (effects (font (size 1.27 1.27)) (justify left bottom))
  )

  (global_label "1V8_SYS" (shape input) (at 252.095 78.105 180) (fields_autoplaced)
    (effects (font (size 1.27 1.27)) (justify right))
    (property "Intersheetrefs" "${INTERSHEET_REFS}" (at 22.225 -15.24 0)
      (effects (font (size 1.27 1.27)) hide)
    )
  )
  (global_label "1V2_SYS" (shape input) (at 329.565 67.945 0) (fields_autoplaced)
    (effects (font (size 1.27 1.27)) (justify left))
    (property "Intersheetrefs" "${INTERSHEET_REFS}" (at -63.5 -129.54 0)
      (effects (font (size 1.27 1.27)) hide)
    )
  )
  (global_label "1V0_SYS" (shape input) (at 252.095 83.185 180) (fields_autoplaced)
    (effects (font (size 1.27 1.27)) (justify right))
    (property "Intersheetrefs" "${INTERSHEET_REFS}" (at 22.225 -12.7 0)
      (effects (font (size 1.27 1.27)) hide)
    )
  )
  (global_label "VDDQ" (shape input) (at 26.67 131.445 180) (fields_autoplaced)
    (effects (font (size 1.27 1.27)) (justify right))
    (property "Intersheetrefs" "${INTERSHEET_REFS}" (at 19.3868 131.5244 0)
      (effects (font (size 1.27 1.27)) (justify right) hide)
    )
  )
  (global_label "1V8_SYS" (shape input) (at 27.94 100.965 180) (fields_autoplaced)
    (effects (font (size 1.27 1.27)) (justify right))
    (property "Intersheetrefs" "${INTERSHEET_REFS}" (at 17.6329 101.0444 0)
      (effects (font (size 1.27 1.27)) (justify right) hide)
    )
  )
  (global_label "1V0_SYS" (shape input) (at 132.08 28.575 180) (fields_autoplaced)
    (effects (font (size 1.27 1.27)) (justify right))
    (property "Intersheetrefs" "${INTERSHEET_REFS}" (at 121.7729 28.6544 0)
      (effects (font (size 1.27 1.27)) (justify right) hide)
    )
  )
  (global_label "1V0_SYS" (shape input) (at 252.095 109.22 180) (fields_autoplaced)
    (effects (font (size 1.27 1.27)) (justify right))
    (property "Intersheetrefs" "${INTERSHEET_REFS}" (at 241.7879 109.1406 0)
      (effects (font (size 1.27 1.27)) (justify right) hide)
    )
  )
  (global_label "3V3_SYS" (shape input) (at 24.765 228.6 180) (fields_autoplaced)
    (effects (font (size 1.27 1.27)) (justify right))
    (property "Intersheetrefs" "${INTERSHEET_REFS}" (at 14.4579 228.6794 0)
      (effects (font (size 1.27 1.27)) (justify right) hide)
    )
  )
  (global_label "1V0_SYS" (shape input) (at 252.095 57.785 180) (fields_autoplaced)
    (effects (font (size 1.27 1.27)) (justify right))
    (property "Intersheetrefs" "${INTERSHEET_REFS}" (at 194.945 344.805 0)
      (effects (font (size 1.27 1.27)) hide)
    )
  )
  (global_label "1V8_SYS" (shape input) (at 252.095 62.865 180) (fields_autoplaced)
    (effects (font (size 1.27 1.27)) (justify right))
    (property "Intersheetrefs" "${INTERSHEET_REFS}" (at 194.945 299.085 0)
      (effects (font (size 1.27 1.27)) hide)
    )
  )
  (global_label "1V8_SYS" (shape input) (at 252.095 70.485 180) (fields_autoplaced)
    (effects (font (size 1.27 1.27)) (justify right))
    (property "Intersheetrefs" "${INTERSHEET_REFS}" (at 22.225 -20.32 0)
      (effects (font (size 1.27 1.27)) hide)
    )
  )
  (global_label "1V0_SYS" (shape input) (at 329.565 57.785 0) (fields_autoplaced)
    (effects (font (size 1.27 1.27)) (justify left))
    (property "Intersheetrefs" "${INTERSHEET_REFS}" (at -63.5 -146.05 0)
      (effects (font (size 1.27 1.27)) hide)
    )
  )
  (global_label "1V2_SYS" (shape input) (at 329.565 70.485 0) (fields_autoplaced)
    (effects (font (size 1.27 1.27)) (justify left))
    (property "Intersheetrefs" "${INTERSHEET_REFS}" (at -63.5 -127 0)
      (effects (font (size 1.27 1.27)) hide)
    )
  )
  (global_label "1V8_SYS" (shape input) (at 329.565 62.865 0) (fields_autoplaced)
    (effects (font (size 1.27 1.27)) (justify left))
    (property "Intersheetrefs" "${INTERSHEET_REFS}" (at -62.865 -127.635 0)
      (effects (font (size 1.27 1.27)) hide)
    )
  )
  (global_label "1V0_SYS" (shape input) (at 27.94 63.5 180) (fields_autoplaced)
    (effects (font (size 1.27 1.27)) (justify right))
    (property "Intersheetrefs" "${INTERSHEET_REFS}" (at 17.6329 63.5794 0)
      (effects (font (size 1.27 1.27)) (justify right) hide)
    )
  )
  (global_label "VDDQ" (shape input) (at 26.67 166.37 180) (fields_autoplaced)
    (effects (font (size 1.27 1.27)) (justify right))
    (property "Intersheetrefs" "${INTERSHEET_REFS}" (at 19.3868 166.4494 0)
      (effects (font (size 1.27 1.27)) (justify right) hide)
    )
  )
  (global_label "1V8_SYS" (shape input) (at 139.7 100.965 180) (fields_autoplaced)
    (effects (font (size 1.27 1.27)) (justify right))
    (property "Intersheetrefs" "${INTERSHEET_REFS}" (at 129.3929 101.0444 0)
      (effects (font (size 1.27 1.27)) (justify right) hide)
    )
  )
  (global_label "3V3_SYS" (shape input) (at 25.4 197.485 180) (fields_autoplaced)
    (effects (font (size 1.27 1.27)) (justify right))
    (property "Intersheetrefs" "${INTERSHEET_REFS}" (at 15.0929 197.5644 0)
      (effects (font (size 1.27 1.27)) (justify right) hide)
    )
  )
  (global_label "1V2_SYS" (shape input) (at 315.595 109.22 180) (fields_autoplaced)
    (effects (font (size 1.27 1.27)) (justify right))
    (property "Intersheetrefs" "${INTERSHEET_REFS}" (at 305.2879 109.1406 0)
      (effects (font (size 1.27 1.27)) (justify right) hide)
    )
  )
  (global_label "1V8_SYS" (shape input) (at 217.805 109.22 180) (fields_autoplaced)
    (effects (font (size 1.27 1.27)) (justify right))
    (property "Intersheetrefs" "${INTERSHEET_REFS}" (at 207.4979 109.1406 0)
      (effects (font (size 1.27 1.27)) (justify right) hide)
    )
  )

  (symbol (lib_id "antmicroCapacitorsmisc:C_100n_0201") (at 58.42 135.255 270) (unit 1)
    (in_bom yes) (on_board yes) (dnp no)
    (property "Reference" "C32" (at 58.42 135.89 90)
      (effects (font (size 1.524 1.524)) (justify left))
    )
    (property "Value" "C_100n_0201" (at 48.26 155.575 0)
      (effects (font (size 1.27 1.27) (thickness 0.15)) (justify left bottom) hide)
    )
    (property "Footprint" "antmicro-footprints:C_0201" (at 45.72 155.575 0)
      (effects (font (size 1.27 1.27) (thickness 0.15)) (justify left bottom) hide)
    )
    (property "Datasheet" " " (at 43.18 155.575 0)
      (effects (font (size 1.27 1.27) (thickness 0.15)) (justify left bottom) hide)
    )
    (property "Manufacturer" "Yaego" (at 38.1 155.575 0)
      (effects (font (size 1.27 1.27) (thickness 0.15)) (justify left bottom) hide)
    )
    (property "MPN" "CC0201KRX6S5BB104" (at 40.64 155.575 0)
      (effects (font (size 1.27 1.27) (thickness 0.15)) (justify left bottom) hide)
    )
    (property "Val" "100n" (at 58.42 139.7 90)
      (effects (font (size 1.27 1.27) (thickness 0.15)) (justify left))
    )
    (property "License" "Apache-2.0" (at 35.56 155.575 0)
      (effects (font (size 1.27 1.27) (thickness 0.15)) (justify left bottom) hide)
    )
    (property "Author" "Antmicro" (at 33.02 155.575 0)
      (effects (font (size 1.27 1.27) (thickness 0.15)) (justify left bottom) hide)
    )
    (property "Voltage" "" (at 30.48 155.575 0)
      (effects (font (size 1.27 1.27)) (justify left bottom) hide)
    )
    (property "Dielectric" "" (at 27.94 155.575 0)
      (effects (font (size 1.27 1.27)) (justify left bottom) hide)
    )
    (pin "1")
    (pin "2")
    (instances
      (project "data-center-rdimm-ddr4-tester"
        (path ""
          (reference "C32") (unit 1)
        )
      )
    )
  )

  (symbol (lib_id "antmicroCapacitorsmisc:C_100n_0201") (at 65.405 135.255 270) (unit 1)
    (in_bom yes) (on_board yes) (dnp no)
    (property "Reference" "C34" (at 65.405 135.89 90)
      (effects (font (size 1.524 1.524)) (justify left))
    )
    (property "Value" "C_100n_0201" (at 55.245 155.575 0)
      (effects (font (size 1.27 1.27) (thickness 0.15)) (justify left bottom) hide)
    )
    (property "Footprint" "antmicro-footprints:C_0201" (at 52.705 155.575 0)
      (effects (font (size 1.27 1.27) (thickness 0.15)) (justify left bottom) hide)
    )
    (property "Datasheet" " " (at 50.165 155.575 0)
      (effects (font (size 1.27 1.27) (thickness 0.15)) (justify left bottom) hide)
    )
    (property "Manufacturer" "Yaego" (at 45.085 155.575 0)
      (effects (font (size 1.27 1.27) (thickness 0.15)) (justify left bottom) hide)
    )
    (property "MPN" "CC0201KRX6S5BB104" (at 47.625 155.575 0)
      (effects (font (size 1.27 1.27) (thickness 0.15)) (justify left bottom) hide)
    )
    (property "Val" "100n" (at 65.405 139.7 90)
      (effects (font (size 1.27 1.27) (thickness 0.15)) (justify left))
    )
    (property "License" "Apache-2.0" (at 42.545 155.575 0)
      (effects (font (size 1.27 1.27) (thickness 0.15)) (justify left bottom) hide)
    )
    (property "Author" "Antmicro" (at 40.005 155.575 0)
      (effects (font (size 1.27 1.27) (thickness 0.15)) (justify left bottom) hide)
    )
    (property "Voltage" "" (at 37.465 155.575 0)
      (effects (font (size 1.27 1.27)) (justify left bottom) hide)
    )
    (property "Dielectric" "" (at 34.925 155.575 0)
      (effects (font (size 1.27 1.27)) (justify left bottom) hide)
    )
    (pin "1")
    (pin "2")
    (instances
      (project "data-center-rdimm-ddr4-tester"
        (path ""
          (reference "C34") (unit 1)
        )
      )
    )
  )

  (symbol (lib_id "antmicroCapacitorsmisc:C_100n_0201") (at 72.39 135.255 270) (unit 1)
    (in_bom yes) (on_board yes) (dnp no)
    (property "Reference" "C43" (at 72.39 135.89 90)
      (effects (font (size 1.524 1.524)) (justify left))
    )
    (property "Value" "C_100n_0201" (at 62.23 155.575 0)
      (effects (font (size 1.27 1.27) (thickness 0.15)) (justify left bottom) hide)
    )
    (property "Footprint" "antmicro-footprints:C_0201" (at 59.69 155.575 0)
      (effects (font (size 1.27 1.27) (thickness 0.15)) (justify left bottom) hide)
    )
    (property "Datasheet" " " (at 57.15 155.575 0)
      (effects (font (size 1.27 1.27) (thickness 0.15)) (justify left bottom) hide)
    )
    (property "Manufacturer" "Yaego" (at 52.07 155.575 0)
      (effects (font (size 1.27 1.27) (thickness 0.15)) (justify left bottom) hide)
    )
    (property "MPN" "CC0201KRX6S5BB104" (at 54.61 155.575 0)
      (effects (font (size 1.27 1.27) (thickness 0.15)) (justify left bottom) hide)
    )
    (property "Val" "100n" (at 72.39 139.7 90)
      (effects (font (size 1.27 1.27) (thickness 0.15)) (justify left))
    )
    (property "License" "Apache-2.0" (at 49.53 155.575 0)
      (effects (font (size 1.27 1.27) (thickness 0.15)) (justify left bottom) hide)
    )
    (property "Author" "Antmicro" (at 46.99 155.575 0)
      (effects (font (size 1.27 1.27) (thickness 0.15)) (justify left bottom) hide)
    )
    (property "Voltage" "" (at 44.45 155.575 0)
      (effects (font (size 1.27 1.27)) (justify left bottom) hide)
    )
    (property "Dielectric" "" (at 41.91 155.575 0)
      (effects (font (size 1.27 1.27)) (justify left bottom) hide)
    )
    (pin "1")
    (pin "2")
    (instances
      (project "data-center-rdimm-ddr4-tester"
        (path ""
          (reference "C43") (unit 1)
        )
      )
    )
  )

  (symbol (lib_id "antmicroCapacitorsmisc:C_100n_0201") (at 79.375 135.255 270) (unit 1)
    (in_bom yes) (on_board yes) (dnp no)
    (property "Reference" "C44" (at 79.375 135.89 90)
      (effects (font (size 1.524 1.524)) (justify left))
    )
    (property "Value" "C_100n_0201" (at 69.215 155.575 0)
      (effects (font (size 1.27 1.27) (thickness 0.15)) (justify left bottom) hide)
    )
    (property "Footprint" "antmicro-footprints:C_0201" (at 66.675 155.575 0)
      (effects (font (size 1.27 1.27) (thickness 0.15)) (justify left bottom) hide)
    )
    (property "Datasheet" " " (at 64.135 155.575 0)
      (effects (font (size 1.27 1.27) (thickness 0.15)) (justify left bottom) hide)
    )
    (property "Manufacturer" "Yaego" (at 59.055 155.575 0)
      (effects (font (size 1.27 1.27) (thickness 0.15)) (justify left bottom) hide)
    )
    (property "MPN" "CC0201KRX6S5BB104" (at 61.595 155.575 0)
      (effects (font (size 1.27 1.27) (thickness 0.15)) (justify left bottom) hide)
    )
    (property "Val" "100n" (at 79.375 139.7 90)
      (effects (font (size 1.27 1.27) (thickness 0.15)) (justify left))
    )
    (property "License" "Apache-2.0" (at 56.515 155.575 0)
      (effects (font (size 1.27 1.27) (thickness 0.15)) (justify left bottom) hide)
    )
    (property "Author" "Antmicro" (at 53.975 155.575 0)
      (effects (font (size 1.27 1.27) (thickness 0.15)) (justify left bottom) hide)
    )
    (property "Voltage" "" (at 51.435 155.575 0)
      (effects (font (size 1.27 1.27)) (justify left bottom) hide)
    )
    (property "Dielectric" "" (at 48.895 155.575 0)
      (effects (font (size 1.27 1.27)) (justify left bottom) hide)
    )
    (pin "1")
    (pin "2")
    (instances
      (project "data-center-rdimm-ddr4-tester"
        (path ""
          (reference "C44") (unit 1)
        )
      )
    )
  )

  (symbol (lib_id "antmicroCapacitorsmisc:C_100n_0201") (at 86.36 135.255 270) (unit 1)
    (in_bom yes) (on_board yes) (dnp no)
    (property "Reference" "C71" (at 86.36 135.89 90)
      (effects (font (size 1.524 1.524)) (justify left))
    )
    (property "Value" "C_100n_0201" (at 76.2 155.575 0)
      (effects (font (size 1.27 1.27) (thickness 0.15)) (justify left bottom) hide)
    )
    (property "Footprint" "antmicro-footprints:C_0201" (at 73.66 155.575 0)
      (effects (font (size 1.27 1.27) (thickness 0.15)) (justify left bottom) hide)
    )
    (property "Datasheet" " " (at 71.12 155.575 0)
      (effects (font (size 1.27 1.27) (thickness 0.15)) (justify left bottom) hide)
    )
    (property "Manufacturer" "Yaego" (at 66.04 155.575 0)
      (effects (font (size 1.27 1.27) (thickness 0.15)) (justify left bottom) hide)
    )
    (property "MPN" "CC0201KRX6S5BB104" (at 68.58 155.575 0)
      (effects (font (size 1.27 1.27) (thickness 0.15)) (justify left bottom) hide)
    )
    (property "Val" "100n" (at 86.36 139.7 90)
      (effects (font (size 1.27 1.27) (thickness 0.15)) (justify left))
    )
    (property "License" "Apache-2.0" (at 63.5 155.575 0)
      (effects (font (size 1.27 1.27) (thickness 0.15)) (justify left bottom) hide)
    )
    (property "Author" "Antmicro" (at 60.96 155.575 0)
      (effects (font (size 1.27 1.27) (thickness 0.15)) (justify left bottom) hide)
    )
    (property "Voltage" "" (at 58.42 155.575 0)
      (effects (font (size 1.27 1.27)) (justify left bottom) hide)
    )
    (property "Dielectric" "" (at 55.88 155.575 0)
      (effects (font (size 1.27 1.27)) (justify left bottom) hide)
    )
    (pin "1")
    (pin "2")
    (instances
      (project "data-center-rdimm-ddr4-tester"
        (path ""
          (reference "C71") (unit 1)
        )
      )
    )
  )

  (symbol (lib_id "antmicropower:GND") (at 86.36 140.335 0) (unit 1)
    (in_bom yes) (on_board yes) (dnp no) (fields_autoplaced)
    (property "Reference" "#PWR010" (at 86.36 146.685 0)
      (effects (font (size 1.27 1.27)) hide)
    )
    (property "Value" "GND" (at 86.36 145.415 0)
      (effects (font (size 1.27 1.27)))
    )
    (property "Footprint" "" (at 86.36 140.335 0)
      (effects (font (size 1.27 1.27)) hide)
    )
    (property "Datasheet" "" (at 86.36 140.335 0)
      (effects (font (size 1.27 1.27)) hide)
    )
    (property "Author" "Antmicro" (at 95.25 147.955 0)
      (effects (font (size 1.27 1.27) (thickness 0.15)) (justify left bottom) hide)
    )
    (property "License" "Apache-2.0" (at 95.25 150.495 0)
      (effects (font (size 1.27 1.27) (thickness 0.15)) (justify left bottom) hide)
    )
    (pin "1")
    (instances
      (project "data-center-rdimm-ddr4-tester"
        (path ""
          (reference "#PWR010") (unit 1)
        )
      )
    )
  )

  (symbol (lib_id "antmicropower:GND") (at 79.375 140.335 0) (unit 1)
    (in_bom yes) (on_board yes) (dnp no) (fields_autoplaced)
    (property "Reference" "#PWR09" (at 79.375 146.685 0)
      (effects (font (size 1.27 1.27)) hide)
    )
    (property "Value" "GND" (at 79.375 145.415 0)
      (effects (font (size 1.27 1.27)))
    )
    (property "Footprint" "" (at 79.375 140.335 0)
      (effects (font (size 1.27 1.27)) hide)
    )
    (property "Datasheet" "" (at 79.375 140.335 0)
      (effects (font (size 1.27 1.27)) hide)
    )
    (property "Author" "Antmicro" (at 88.265 147.955 0)
      (effects (font (size 1.27 1.27) (thickness 0.15)) (justify left bottom) hide)
    )
    (property "License" "Apache-2.0" (at 88.265 150.495 0)
      (effects (font (size 1.27 1.27) (thickness 0.15)) (justify left bottom) hide)
    )
    (pin "1")
    (instances
      (project "data-center-rdimm-ddr4-tester"
        (path ""
          (reference "#PWR09") (unit 1)
        )
      )
    )
  )

  (symbol (lib_id "antmicropower:GND") (at 72.39 140.335 0) (unit 1)
    (in_bom yes) (on_board yes) (dnp no) (fields_autoplaced)
    (property "Reference" "#PWR08" (at 72.39 146.685 0)
      (effects (font (size 1.27 1.27)) hide)
    )
    (property "Value" "GND" (at 72.39 145.415 0)
      (effects (font (size 1.27 1.27)))
    )
    (property "Footprint" "" (at 72.39 140.335 0)
      (effects (font (size 1.27 1.27)) hide)
    )
    (property "Datasheet" "" (at 72.39 140.335 0)
      (effects (font (size 1.27 1.27)) hide)
    )
    (property "Author" "Antmicro" (at 81.28 147.955 0)
      (effects (font (size 1.27 1.27) (thickness 0.15)) (justify left bottom) hide)
    )
    (property "License" "Apache-2.0" (at 81.28 150.495 0)
      (effects (font (size 1.27 1.27) (thickness 0.15)) (justify left bottom) hide)
    )
    (pin "1")
    (instances
      (project "data-center-rdimm-ddr4-tester"
        (path ""
          (reference "#PWR08") (unit 1)
        )
      )
    )
  )

  (symbol (lib_id "antmicropower:GND") (at 65.405 140.335 0) (unit 1)
    (in_bom yes) (on_board yes) (dnp no) (fields_autoplaced)
    (property "Reference" "#PWR07" (at 65.405 146.685 0)
      (effects (font (size 1.27 1.27)) hide)
    )
    (property "Value" "GND" (at 65.405 145.415 0)
      (effects (font (size 1.27 1.27)))
    )
    (property "Footprint" "" (at 65.405 140.335 0)
      (effects (font (size 1.27 1.27)) hide)
    )
    (property "Datasheet" "" (at 65.405 140.335 0)
      (effects (font (size 1.27 1.27)) hide)
    )
    (property "Author" "Antmicro" (at 74.295 147.955 0)
      (effects (font (size 1.27 1.27) (thickness 0.15)) (justify left bottom) hide)
    )
    (property "License" "Apache-2.0" (at 74.295 150.495 0)
      (effects (font (size 1.27 1.27) (thickness 0.15)) (justify left bottom) hide)
    )
    (pin "1")
    (instances
      (project "data-center-rdimm-ddr4-tester"
        (path ""
          (reference "#PWR07") (unit 1)
        )
      )
    )
  )

  (symbol (lib_id "antmicropower:GND") (at 58.42 140.335 0) (unit 1)
    (in_bom yes) (on_board yes) (dnp no) (fields_autoplaced)
    (property "Reference" "#PWR06" (at 58.42 146.685 0)
      (effects (font (size 1.27 1.27)) hide)
    )
    (property "Value" "GND" (at 58.42 144.78 0)
      (effects (font (size 1.27 1.27)))
    )
    (property "Footprint" "" (at 58.42 140.335 0)
      (effects (font (size 1.27 1.27)) hide)
    )
    (property "Datasheet" "" (at 58.42 140.335 0)
      (effects (font (size 1.27 1.27)) hide)
    )
    (property "Author" "Antmicro" (at 67.31 147.955 0)
      (effects (font (size 1.27 1.27) (thickness 0.15)) (justify left bottom) hide)
    )
    (property "License" "Apache-2.0" (at 67.31 150.495 0)
      (effects (font (size 1.27 1.27) (thickness 0.15)) (justify left bottom) hide)
    )
    (pin "1")
    (instances
      (project "data-center-rdimm-ddr4-tester"
        (path ""
          (reference "#PWR06") (unit 1)
        )
      )
    )
  )

  (symbol (lib_id "antmicroCapacitorsmisc:C_100n_0201") (at 93.345 135.255 270) (unit 1)
    (in_bom yes) (on_board yes) (dnp no)
    (property "Reference" "C72" (at 93.345 135.89 90)
      (effects (font (size 1.524 1.524)) (justify left))
    )
    (property "Value" "C_100n_0201" (at 83.185 155.575 0)
      (effects (font (size 1.27 1.27) (thickness 0.15)) (justify left bottom) hide)
    )
    (property "Footprint" "antmicro-footprints:C_0201" (at 80.645 155.575 0)
      (effects (font (size 1.27 1.27) (thickness 0.15)) (justify left bottom) hide)
    )
    (property "Datasheet" " " (at 78.105 155.575 0)
      (effects (font (size 1.27 1.27) (thickness 0.15)) (justify left bottom) hide)
    )
    (property "Manufacturer" "Yaego" (at 73.025 155.575 0)
      (effects (font (size 1.27 1.27) (thickness 0.15)) (justify left bottom) hide)
    )
    (property "MPN" "CC0201KRX6S5BB104" (at 75.565 155.575 0)
      (effects (font (size 1.27 1.27) (thickness 0.15)) (justify left bottom) hide)
    )
    (property "Val" "100n" (at 93.345 139.7 90)
      (effects (font (size 1.27 1.27) (thickness 0.15)) (justify left))
    )
    (property "License" "Apache-2.0" (at 70.485 155.575 0)
      (effects (font (size 1.27 1.27) (thickness 0.15)) (justify left bottom) hide)
    )
    (property "Author" "Antmicro" (at 67.945 155.575 0)
      (effects (font (size 1.27 1.27) (thickness 0.15)) (justify left bottom) hide)
    )
    (property "Voltage" "" (at 65.405 155.575 0)
      (effects (font (size 1.27 1.27)) (justify left bottom) hide)
    )
    (property "Dielectric" "" (at 62.865 155.575 0)
      (effects (font (size 1.27 1.27)) (justify left bottom) hide)
    )
    (pin "1")
    (pin "2")
    (instances
      (project "data-center-rdimm-ddr4-tester"
        (path ""
          (reference "C72") (unit 1)
        )
      )
    )
  )

  (symbol (lib_id "antmicropower:GND") (at 93.345 140.335 0) (unit 1)
    (in_bom yes) (on_board yes) (dnp no) (fields_autoplaced)
    (property "Reference" "#PWR011" (at 93.345 146.685 0)
      (effects (font (size 1.27 1.27)) hide)
    )
    (property "Value" "GND" (at 93.345 145.415 0)
      (effects (font (size 1.27 1.27)))
    )
    (property "Footprint" "" (at 93.345 140.335 0)
      (effects (font (size 1.27 1.27)) hide)
    )
    (property "Datasheet" "" (at 93.345 140.335 0)
      (effects (font (size 1.27 1.27)) hide)
    )
    (property "Author" "Antmicro" (at 102.235 147.955 0)
      (effects (font (size 1.27 1.27) (thickness 0.15)) (justify left bottom) hide)
    )
    (property "License" "Apache-2.0" (at 102.235 150.495 0)
      (effects (font (size 1.27 1.27) (thickness 0.15)) (justify left bottom) hide)
    )
    (pin "1")
    (instances
      (project "data-center-rdimm-ddr4-tester"
        (path ""
          (reference "#PWR011") (unit 1)
        )
      )
    )
  )

  (symbol (lib_id "antmicroCapacitorsmisc:C_100n_0201") (at 100.33 135.255 270) (unit 1)
    (in_bom yes) (on_board yes) (dnp no)
    (property "Reference" "C73" (at 100.33 135.89 90)
      (effects (font (size 1.524 1.524)) (justify left))
    )
    (property "Value" "C_100n_0201" (at 90.17 155.575 0)
      (effects (font (size 1.27 1.27) (thickness 0.15)) (justify left bottom) hide)
    )
    (property "Footprint" "antmicro-footprints:C_0201" (at 87.63 155.575 0)
      (effects (font (size 1.27 1.27) (thickness 0.15)) (justify left bottom) hide)
    )
    (property "Datasheet" " " (at 85.09 155.575 0)
      (effects (font (size 1.27 1.27) (thickness 0.15)) (justify left bottom) hide)
    )
    (property "Manufacturer" "Yaego" (at 80.01 155.575 0)
      (effects (font (size 1.27 1.27) (thickness 0.15)) (justify left bottom) hide)
    )
    (property "MPN" "CC0201KRX6S5BB104" (at 82.55 155.575 0)
      (effects (font (size 1.27 1.27) (thickness 0.15)) (justify left bottom) hide)
    )
    (property "Val" "100n" (at 100.33 139.7 90)
      (effects (font (size 1.27 1.27) (thickness 0.15)) (justify left))
    )
    (property "License" "Apache-2.0" (at 77.47 155.575 0)
      (effects (font (size 1.27 1.27) (thickness 0.15)) (justify left bottom) hide)
    )
    (property "Author" "Antmicro" (at 74.93 155.575 0)
      (effects (font (size 1.27 1.27) (thickness 0.15)) (justify left bottom) hide)
    )
    (property "Voltage" "" (at 72.39 155.575 0)
      (effects (font (size 1.27 1.27)) (justify left bottom) hide)
    )
    (property "Dielectric" "" (at 69.85 155.575 0)
      (effects (font (size 1.27 1.27)) (justify left bottom) hide)
    )
    (pin "1")
    (pin "2")
    (instances
      (project "data-center-rdimm-ddr4-tester"
        (path ""
          (reference "C73") (unit 1)
        )
      )
    )
  )

  (symbol (lib_id "antmicropower:GND") (at 100.33 140.335 0) (unit 1)
    (in_bom yes) (on_board yes) (dnp no) (fields_autoplaced)
    (property "Reference" "#PWR012" (at 100.33 146.685 0)
      (effects (font (size 1.27 1.27)) hide)
    )
    (property "Value" "GND" (at 100.33 145.415 0)
      (effects (font (size 1.27 1.27)))
    )
    (property "Footprint" "" (at 100.33 140.335 0)
      (effects (font (size 1.27 1.27)) hide)
    )
    (property "Datasheet" "" (at 100.33 140.335 0)
      (effects (font (size 1.27 1.27)) hide)
    )
    (property "Author" "Antmicro" (at 109.22 147.955 0)
      (effects (font (size 1.27 1.27) (thickness 0.15)) (justify left bottom) hide)
    )
    (property "License" "Apache-2.0" (at 109.22 150.495 0)
      (effects (font (size 1.27 1.27) (thickness 0.15)) (justify left bottom) hide)
    )
    (pin "1")
    (instances
      (project "data-center-rdimm-ddr4-tester"
        (path ""
          (reference "#PWR012") (unit 1)
        )
      )
    )
  )

  (symbol (lib_id "antmicroCapacitorsmisc:C_100n_0201") (at 107.315 135.255 270) (unit 1)
    (in_bom yes) (on_board yes) (dnp no)
    (property "Reference" "C74" (at 107.315 135.89 90)
      (effects (font (size 1.524 1.524)) (justify left))
    )
    (property "Value" "C_100n_0201" (at 97.155 155.575 0)
      (effects (font (size 1.27 1.27) (thickness 0.15)) (justify left bottom) hide)
    )
    (property "Footprint" "antmicro-footprints:C_0201" (at 94.615 155.575 0)
      (effects (font (size 1.27 1.27) (thickness 0.15)) (justify left bottom) hide)
    )
    (property "Datasheet" " " (at 92.075 155.575 0)
      (effects (font (size 1.27 1.27) (thickness 0.15)) (justify left bottom) hide)
    )
    (property "Manufacturer" "Yaego" (at 86.995 155.575 0)
      (effects (font (size 1.27 1.27) (thickness 0.15)) (justify left bottom) hide)
    )
    (property "MPN" "CC0201KRX6S5BB104" (at 89.535 155.575 0)
      (effects (font (size 1.27 1.27) (thickness 0.15)) (justify left bottom) hide)
    )
    (property "Val" "100n" (at 107.315 139.7 90)
      (effects (font (size 1.27 1.27) (thickness 0.15)) (justify left))
    )
    (property "License" "Apache-2.0" (at 84.455 155.575 0)
      (effects (font (size 1.27 1.27) (thickness 0.15)) (justify left bottom) hide)
    )
    (property "Author" "Antmicro" (at 81.915 155.575 0)
      (effects (font (size 1.27 1.27) (thickness 0.15)) (justify left bottom) hide)
    )
    (property "Voltage" "" (at 79.375 155.575 0)
      (effects (font (size 1.27 1.27)) (justify left bottom) hide)
    )
    (property "Dielectric" "" (at 76.835 155.575 0)
      (effects (font (size 1.27 1.27)) (justify left bottom) hide)
    )
    (pin "1")
    (pin "2")
    (instances
      (project "data-center-rdimm-ddr4-tester"
        (path ""
          (reference "C74") (unit 1)
        )
      )
    )
  )

  (symbol (lib_id "antmicropower:GND") (at 107.315 140.335 0) (unit 1)
    (in_bom yes) (on_board yes) (dnp no) (fields_autoplaced)
    (property "Reference" "#PWR013" (at 107.315 146.685 0)
      (effects (font (size 1.27 1.27)) hide)
    )
    (property "Value" "GND" (at 107.315 145.415 0)
      (effects (font (size 1.27 1.27)))
    )
    (property "Footprint" "" (at 107.315 140.335 0)
      (effects (font (size 1.27 1.27)) hide)
    )
    (property "Datasheet" "" (at 107.315 140.335 0)
      (effects (font (size 1.27 1.27)) hide)
    )
    (property "Author" "Antmicro" (at 116.205 147.955 0)
      (effects (font (size 1.27 1.27) (thickness 0.15)) (justify left bottom) hide)
    )
    (property "License" "Apache-2.0" (at 116.205 150.495 0)
      (effects (font (size 1.27 1.27) (thickness 0.15)) (justify left bottom) hide)
    )
    (pin "1")
    (instances
      (project "data-center-rdimm-ddr4-tester"
        (path ""
          (reference "#PWR013") (unit 1)
        )
      )
    )
  )

  (symbol (lib_id "antmicroCapacitorsmisc:C_100n_0201") (at 114.3 135.255 270) (unit 1)
    (in_bom yes) (on_board yes) (dnp no)
    (property "Reference" "C75" (at 114.3 135.89 90)
      (effects (font (size 1.524 1.524)) (justify left))
    )
    (property "Value" "C_100n_0201" (at 104.14 155.575 0)
      (effects (font (size 1.27 1.27) (thickness 0.15)) (justify left bottom) hide)
    )
    (property "Footprint" "antmicro-footprints:C_0201" (at 101.6 155.575 0)
      (effects (font (size 1.27 1.27) (thickness 0.15)) (justify left bottom) hide)
    )
    (property "Datasheet" " " (at 99.06 155.575 0)
      (effects (font (size 1.27 1.27) (thickness 0.15)) (justify left bottom) hide)
    )
    (property "Manufacturer" "Yaego" (at 93.98 155.575 0)
      (effects (font (size 1.27 1.27) (thickness 0.15)) (justify left bottom) hide)
    )
    (property "MPN" "CC0201KRX6S5BB104" (at 96.52 155.575 0)
      (effects (font (size 1.27 1.27) (thickness 0.15)) (justify left bottom) hide)
    )
    (property "Val" "100n" (at 114.3 139.7 90)
      (effects (font (size 1.27 1.27) (thickness 0.15)) (justify left))
    )
    (property "License" "Apache-2.0" (at 91.44 155.575 0)
      (effects (font (size 1.27 1.27) (thickness 0.15)) (justify left bottom) hide)
    )
    (property "Author" "Antmicro" (at 88.9 155.575 0)
      (effects (font (size 1.27 1.27) (thickness 0.15)) (justify left bottom) hide)
    )
    (property "Voltage" "" (at 86.36 155.575 0)
      (effects (font (size 1.27 1.27)) (justify left bottom) hide)
    )
    (property "Dielectric" "" (at 83.82 155.575 0)
      (effects (font (size 1.27 1.27)) (justify left bottom) hide)
    )
    (pin "1")
    (pin "2")
    (instances
      (project "data-center-rdimm-ddr4-tester"
        (path ""
          (reference "C75") (unit 1)
        )
      )
    )
  )

  (symbol (lib_id "antmicropower:GND") (at 114.3 140.335 0) (unit 1)
    (in_bom yes) (on_board yes) (dnp no) (fields_autoplaced)
    (property "Reference" "#PWR0139" (at 114.3 146.685 0)
      (effects (font (size 1.27 1.27)) hide)
    )
    (property "Value" "GND" (at 114.3 145.415 0)
      (effects (font (size 1.27 1.27)))
    )
    (property "Footprint" "" (at 114.3 140.335 0)
      (effects (font (size 1.27 1.27)) hide)
    )
    (property "Datasheet" "" (at 114.3 140.335 0)
      (effects (font (size 1.27 1.27)) hide)
    )
    (property "Author" "Antmicro" (at 123.19 147.955 0)
      (effects (font (size 1.27 1.27) (thickness 0.15)) (justify left bottom) hide)
    )
    (property "License" "Apache-2.0" (at 123.19 150.495 0)
      (effects (font (size 1.27 1.27) (thickness 0.15)) (justify left bottom) hide)
    )
    (pin "1")
    (instances
      (project "data-center-rdimm-ddr4-tester"
        (path ""
          (reference "#PWR0139") (unit 1)
        )
      )
    )
  )

  (symbol (lib_id "antmicroCapacitorsmisc:C_100n_0201") (at 121.285 135.255 270) (unit 1)
    (in_bom yes) (on_board yes) (dnp no)
    (property "Reference" "C76" (at 121.285 135.89 90)
      (effects (font (size 1.524 1.524)) (justify left))
    )
    (property "Value" "C_100n_0201" (at 111.125 155.575 0)
      (effects (font (size 1.27 1.27) (thickness 0.15)) (justify left bottom) hide)
    )
    (property "Footprint" "antmicro-footprints:C_0201" (at 108.585 155.575 0)
      (effects (font (size 1.27 1.27) (thickness 0.15)) (justify left bottom) hide)
    )
    (property "Datasheet" " " (at 106.045 155.575 0)
      (effects (font (size 1.27 1.27) (thickness 0.15)) (justify left bottom) hide)
    )
    (property "Manufacturer" "Yaego" (at 100.965 155.575 0)
      (effects (font (size 1.27 1.27) (thickness 0.15)) (justify left bottom) hide)
    )
    (property "MPN" "CC0201KRX6S5BB104" (at 103.505 155.575 0)
      (effects (font (size 1.27 1.27) (thickness 0.15)) (justify left bottom) hide)
    )
    (property "Val" "100n" (at 121.285 139.7 90)
      (effects (font (size 1.27 1.27) (thickness 0.15)) (justify left))
    )
    (property "License" "Apache-2.0" (at 98.425 155.575 0)
      (effects (font (size 1.27 1.27) (thickness 0.15)) (justify left bottom) hide)
    )
    (property "Author" "Antmicro" (at 95.885 155.575 0)
      (effects (font (size 1.27 1.27) (thickness 0.15)) (justify left bottom) hide)
    )
    (property "Voltage" "" (at 93.345 155.575 0)
      (effects (font (size 1.27 1.27)) (justify left bottom) hide)
    )
    (property "Dielectric" "" (at 90.805 155.575 0)
      (effects (font (size 1.27 1.27)) (justify left bottom) hide)
    )
    (pin "1")
    (pin "2")
    (instances
      (project "data-center-rdimm-ddr4-tester"
        (path ""
          (reference "C76") (unit 1)
        )
      )
    )
  )

  (symbol (lib_id "antmicropower:GND") (at 121.285 140.335 0) (unit 1)
    (in_bom yes) (on_board yes) (dnp no) (fields_autoplaced)
    (property "Reference" "#PWR0155" (at 121.285 146.685 0)
      (effects (font (size 1.27 1.27)) hide)
    )
    (property "Value" "GND" (at 121.285 145.415 0)
      (effects (font (size 1.27 1.27)))
    )
    (property "Footprint" "" (at 121.285 140.335 0)
      (effects (font (size 1.27 1.27)) hide)
    )
    (property "Datasheet" "" (at 121.285 140.335 0)
      (effects (font (size 1.27 1.27)) hide)
    )
    (property "Author" "Antmicro" (at 130.175 147.955 0)
      (effects (font (size 1.27 1.27) (thickness 0.15)) (justify left bottom) hide)
    )
    (property "License" "Apache-2.0" (at 130.175 150.495 0)
      (effects (font (size 1.27 1.27) (thickness 0.15)) (justify left bottom) hide)
    )
    (pin "1")
    (instances
      (project "data-center-rdimm-ddr4-tester"
        (path ""
          (reference "#PWR0155") (unit 1)
        )
      )
    )
  )

  (symbol (lib_id "antmicroCapacitorsmisc:C_100n_0201") (at 128.27 66.04 270) (unit 1)
    (in_bom yes) (on_board yes) (dnp no)
    (property "Reference" "C77" (at 128.27 66.675 90)
      (effects (font (size 1.524 1.524)) (justify left))
    )
    (property "Value" "C_100n_0201" (at 118.11 86.36 0)
      (effects (font (size 1.27 1.27) (thickness 0.15)) (justify left bottom) hide)
    )
    (property "Footprint" "antmicro-footprints:C_0201" (at 115.57 86.36 0)
      (effects (font (size 1.27 1.27) (thickness 0.15)) (justify left bottom) hide)
    )
    (property "Datasheet" " " (at 113.03 86.36 0)
      (effects (font (size 1.27 1.27) (thickness 0.15)) (justify left bottom) hide)
    )
    (property "Manufacturer" "Yaego" (at 107.95 86.36 0)
      (effects (font (size 1.27 1.27) (thickness 0.15)) (justify left bottom) hide)
    )
    (property "MPN" "CC0201KRX6S5BB104" (at 110.49 86.36 0)
      (effects (font (size 1.27 1.27) (thickness 0.15)) (justify left bottom) hide)
    )
    (property "Val" "100n" (at 128.27 70.485 90)
      (effects (font (size 1.27 1.27) (thickness 0.15)) (justify left))
    )
    (property "License" "Apache-2.0" (at 105.41 86.36 0)
      (effects (font (size 1.27 1.27) (thickness 0.15)) (justify left bottom) hide)
    )
    (property "Author" "Antmicro" (at 102.87 86.36 0)
      (effects (font (size 1.27 1.27) (thickness 0.15)) (justify left bottom) hide)
    )
    (property "Voltage" "" (at 100.33 86.36 0)
      (effects (font (size 1.27 1.27)) (justify left bottom) hide)
    )
    (property "Dielectric" "" (at 97.79 86.36 0)
      (effects (font (size 1.27 1.27)) (justify left bottom) hide)
    )
    (pin "1")
    (pin "2")
    (instances
      (project "data-center-rdimm-ddr4-tester"
        (path ""
          (reference "C77") (unit 1)
        )
      )
    )
  )

  (symbol (lib_id "antmicropower:GND") (at 128.27 71.12 0) (mirror y) (unit 1)
    (in_bom yes) (on_board yes) (dnp no) (fields_autoplaced)
    (property "Reference" "#PWR0162" (at 128.27 77.47 0)
      (effects (font (size 1.27 1.27)) hide)
    )
    (property "Value" "GND" (at 128.27 76.2 0)
      (effects (font (size 1.27 1.27)))
    )
    (property "Footprint" "" (at 128.27 71.12 0)
      (effects (font (size 1.27 1.27)) hide)
    )
    (property "Datasheet" "" (at 128.27 71.12 0)
      (effects (font (size 1.27 1.27)) hide)
    )
    (property "Author" "Antmicro" (at 119.38 78.74 0)
      (effects (font (size 1.27 1.27) (thickness 0.15)) (justify left bottom) hide)
    )
    (property "License" "Apache-2.0" (at 119.38 81.28 0)
      (effects (font (size 1.27 1.27) (thickness 0.15)) (justify left bottom) hide)
    )
    (pin "1")
    (instances
      (project "data-center-rdimm-ddr4-tester"
        (path ""
          (reference "#PWR0162") (unit 1)
        )
      )
    )
  )

  (symbol (lib_id "antmicropower:GND") (at 55.88 206.375 0) (unit 1)
    (in_bom yes) (on_board yes) (dnp no) (fields_autoplaced)
    (property "Reference" "#PWR0246" (at 55.88 212.725 0)
      (effects (font (size 1.27 1.27)) hide)
    )
    (property "Value" "GND" (at 55.88 211.455 0)
      (effects (font (size 1.27 1.27)))
    )
    (property "Footprint" "" (at 55.88 206.375 0)
      (effects (font (size 1.27 1.27)) hide)
    )
    (property "Datasheet" "" (at 55.88 206.375 0)
      (effects (font (size 1.27 1.27)) hide)
    )
    (property "Author" "Antmicro" (at 64.77 213.995 0)
      (effects (font (size 1.27 1.27) (thickness 0.15)) (justify left bottom) hide)
    )
    (property "License" "Apache-2.0" (at 64.77 216.535 0)
      (effects (font (size 1.27 1.27) (thickness 0.15)) (justify left bottom) hide)
    )
    (pin "1")
    (instances
      (project "data-center-rdimm-ddr4-tester"
        (path ""
          (reference "#PWR0246") (unit 1)
        )
      )
    )
  )

  (symbol (lib_id "antmicropower:GND") (at 62.865 206.375 0) (unit 1)
    (in_bom yes) (on_board yes) (dnp no) (fields_autoplaced)
    (property "Reference" "#PWR0247" (at 62.865 212.725 0)
      (effects (font (size 1.27 1.27)) hide)
    )
    (property "Value" "GND" (at 62.865 211.455 0)
      (effects (font (size 1.27 1.27)))
    )
    (property "Footprint" "" (at 62.865 206.375 0)
      (effects (font (size 1.27 1.27)) hide)
    )
    (property "Datasheet" "" (at 62.865 206.375 0)
      (effects (font (size 1.27 1.27)) hide)
    )
    (property "Author" "Antmicro" (at 71.755 213.995 0)
      (effects (font (size 1.27 1.27) (thickness 0.15)) (justify left bottom) hide)
    )
    (property "License" "Apache-2.0" (at 71.755 216.535 0)
      (effects (font (size 1.27 1.27) (thickness 0.15)) (justify left bottom) hide)
    )
    (pin "1")
    (instances
      (project "data-center-rdimm-ddr4-tester"
        (path ""
          (reference "#PWR0247") (unit 1)
        )
      )
    )
  )

  (symbol (lib_id "antmicropower:GND") (at 69.215 206.375 0) (unit 1)
    (in_bom yes) (on_board yes) (dnp no) (fields_autoplaced)
    (property "Reference" "#PWR0248" (at 69.215 212.725 0)
      (effects (font (size 1.27 1.27)) hide)
    )
    (property "Value" "GND" (at 69.215 211.455 0)
      (effects (font (size 1.27 1.27)))
    )
    (property "Footprint" "" (at 69.215 206.375 0)
      (effects (font (size 1.27 1.27)) hide)
    )
    (property "Datasheet" "" (at 69.215 206.375 0)
      (effects (font (size 1.27 1.27)) hide)
    )
    (property "Author" "Antmicro" (at 78.105 213.995 0)
      (effects (font (size 1.27 1.27) (thickness 0.15)) (justify left bottom) hide)
    )
    (property "License" "Apache-2.0" (at 78.105 216.535 0)
      (effects (font (size 1.27 1.27) (thickness 0.15)) (justify left bottom) hide)
    )
    (pin "1")
    (instances
      (project "data-center-rdimm-ddr4-tester"
        (path ""
          (reference "#PWR0248") (unit 1)
        )
      )
    )
  )

  (symbol (lib_id "antmicropower:GND") (at 76.2 206.375 0) (unit 1)
    (in_bom yes) (on_board yes) (dnp no) (fields_autoplaced)
    (property "Reference" "#PWR0249" (at 76.2 212.725 0)
      (effects (font (size 1.27 1.27)) hide)
    )
    (property "Value" "GND" (at 76.2 211.455 0)
      (effects (font (size 1.27 1.27)))
    )
    (property "Footprint" "" (at 76.2 206.375 0)
      (effects (font (size 1.27 1.27)) hide)
    )
    (property "Datasheet" "" (at 76.2 206.375 0)
      (effects (font (size 1.27 1.27)) hide)
    )
    (property "Author" "Antmicro" (at 85.09 213.995 0)
      (effects (font (size 1.27 1.27) (thickness 0.15)) (justify left bottom) hide)
    )
    (property "License" "Apache-2.0" (at 85.09 216.535 0)
      (effects (font (size 1.27 1.27) (thickness 0.15)) (justify left bottom) hide)
    )
    (pin "1")
    (instances
      (project "data-center-rdimm-ddr4-tester"
        (path ""
          (reference "#PWR0249") (unit 1)
        )
      )
    )
  )

  (symbol (lib_id "antmicropower:GND") (at 82.55 206.375 0) (unit 1)
    (in_bom yes) (on_board yes) (dnp no) (fields_autoplaced)
    (property "Reference" "#PWR0250" (at 82.55 212.725 0)
      (effects (font (size 1.27 1.27)) hide)
    )
    (property "Value" "GND" (at 82.55 211.455 0)
      (effects (font (size 1.27 1.27)))
    )
    (property "Footprint" "" (at 82.55 206.375 0)
      (effects (font (size 1.27 1.27)) hide)
    )
    (property "Datasheet" "" (at 82.55 206.375 0)
      (effects (font (size 1.27 1.27)) hide)
    )
    (property "Author" "Antmicro" (at 91.44 213.995 0)
      (effects (font (size 1.27 1.27) (thickness 0.15)) (justify left bottom) hide)
    )
    (property "License" "Apache-2.0" (at 91.44 216.535 0)
      (effects (font (size 1.27 1.27) (thickness 0.15)) (justify left bottom) hide)
    )
    (pin "1")
    (instances
      (project "data-center-rdimm-ddr4-tester"
        (path ""
          (reference "#PWR0250") (unit 1)
        )
      )
    )
  )

  (symbol (lib_id "antmicroCapacitorsmisc:C_100n_0201") (at 66.04 104.775 270) (unit 1)
    (in_bom yes) (on_board yes) (dnp no)
    (property "Reference" "C9" (at 66.04 105.41 90)
      (effects (font (size 1.524 1.524)) (justify left))
    )
    (property "Value" "C_100n_0201" (at 55.88 125.095 0)
      (effects (font (size 1.27 1.27) (thickness 0.15)) (justify left bottom) hide)
    )
    (property "Footprint" "antmicro-footprints:C_0201" (at 53.34 125.095 0)
      (effects (font (size 1.27 1.27) (thickness 0.15)) (justify left bottom) hide)
    )
    (property "Datasheet" " " (at 50.8 125.095 0)
      (effects (font (size 1.27 1.27) (thickness 0.15)) (justify left bottom) hide)
    )
    (property "Manufacturer" "Yaego" (at 45.72 125.095 0)
      (effects (font (size 1.27 1.27) (thickness 0.15)) (justify left bottom) hide)
    )
    (property "MPN" "CC0201KRX6S5BB104" (at 48.26 125.095 0)
      (effects (font (size 1.27 1.27) (thickness 0.15)) (justify left bottom) hide)
    )
    (property "Val" "100n" (at 66.04 109.22 90)
      (effects (font (size 1.27 1.27) (thickness 0.15)) (justify left))
    )
    (property "License" "Apache-2.0" (at 43.18 125.095 0)
      (effects (font (size 1.27 1.27) (thickness 0.15)) (justify left bottom) hide)
    )
    (property "Author" "Antmicro" (at 40.64 125.095 0)
      (effects (font (size 1.27 1.27) (thickness 0.15)) (justify left bottom) hide)
    )
    (property "Voltage" "" (at 38.1 125.095 0)
      (effects (font (size 1.27 1.27)) (justify left bottom) hide)
    )
    (property "Dielectric" "" (at 35.56 125.095 0)
      (effects (font (size 1.27 1.27)) (justify left bottom) hide)
    )
    (pin "1")
    (pin "2")
    (instances
      (project "data-center-rdimm-ddr4-tester"
        (path ""
          (reference "C9") (unit 1)
        )
      )
    )
  )

  (symbol (lib_id "antmicropower:GND") (at 66.04 109.855 0) (mirror y) (unit 1)
    (in_bom yes) (on_board yes) (dnp no) (fields_autoplaced)
    (property "Reference" "#PWR0115" (at 66.04 116.205 0)
      (effects (font (size 1.27 1.27)) hide)
    )
    (property "Value" "GND" (at 66.04 114.3 0)
      (effects (font (size 1.27 1.27)))
    )
    (property "Footprint" "" (at 66.04 109.855 0)
      (effects (font (size 1.27 1.27)) hide)
    )
    (property "Datasheet" "" (at 66.04 109.855 0)
      (effects (font (size 1.27 1.27)) hide)
    )
    (property "Author" "Antmicro" (at 57.15 117.475 0)
      (effects (font (size 1.27 1.27) (thickness 0.15)) (justify left bottom) hide)
    )
    (property "License" "Apache-2.0" (at 57.15 120.015 0)
      (effects (font (size 1.27 1.27) (thickness 0.15)) (justify left bottom) hide)
    )
    (pin "1")
    (instances
      (project "data-center-rdimm-ddr4-tester"
        (path ""
          (reference "#PWR0115") (unit 1)
        )
      )
    )
  )

  (symbol (lib_id "antmicropower:GND") (at 89.535 206.375 0) (unit 1)
    (in_bom yes) (on_board yes) (dnp no) (fields_autoplaced)
    (property "Reference" "#PWR0251" (at 89.535 212.725 0)
      (effects (font (size 1.27 1.27)) hide)
    )
    (property "Value" "GND" (at 89.535 211.455 0)
      (effects (font (size 1.27 1.27)))
    )
    (property "Footprint" "" (at 89.535 206.375 0)
      (effects (font (size 1.27 1.27)) hide)
    )
    (property "Datasheet" "" (at 89.535 206.375 0)
      (effects (font (size 1.27 1.27)) hide)
    )
    (property "Author" "Antmicro" (at 98.425 213.995 0)
      (effects (font (size 1.27 1.27) (thickness 0.15)) (justify left bottom) hide)
    )
    (property "License" "Apache-2.0" (at 98.425 216.535 0)
      (effects (font (size 1.27 1.27) (thickness 0.15)) (justify left bottom) hide)
    )
    (pin "1")
    (instances
      (project "data-center-rdimm-ddr4-tester"
        (path ""
          (reference "#PWR0251") (unit 1)
        )
      )
    )
  )

  (symbol (lib_id "antmicroCapacitorsmisc:C_100n_0201") (at 73.025 104.775 270) (unit 1)
    (in_bom yes) (on_board yes) (dnp no)
    (property "Reference" "C47" (at 73.025 105.41 90)
      (effects (font (size 1.524 1.524)) (justify left))
    )
    (property "Value" "C_100n_0201" (at 62.865 125.095 0)
      (effects (font (size 1.27 1.27) (thickness 0.15)) (justify left bottom) hide)
    )
    (property "Footprint" "antmicro-footprints:C_0201" (at 60.325 125.095 0)
      (effects (font (size 1.27 1.27) (thickness 0.15)) (justify left bottom) hide)
    )
    (property "Datasheet" " " (at 57.785 125.095 0)
      (effects (font (size 1.27 1.27) (thickness 0.15)) (justify left bottom) hide)
    )
    (property "Manufacturer" "Yaego" (at 52.705 125.095 0)
      (effects (font (size 1.27 1.27) (thickness 0.15)) (justify left bottom) hide)
    )
    (property "MPN" "CC0201KRX6S5BB104" (at 55.245 125.095 0)
      (effects (font (size 1.27 1.27) (thickness 0.15)) (justify left bottom) hide)
    )
    (property "Val" "100n" (at 73.025 109.22 90)
      (effects (font (size 1.27 1.27) (thickness 0.15)) (justify left))
    )
    (property "License" "Apache-2.0" (at 50.165 125.095 0)
      (effects (font (size 1.27 1.27) (thickness 0.15)) (justify left bottom) hide)
    )
    (property "Author" "Antmicro" (at 47.625 125.095 0)
      (effects (font (size 1.27 1.27) (thickness 0.15)) (justify left bottom) hide)
    )
    (property "Voltage" "" (at 45.085 125.095 0)
      (effects (font (size 1.27 1.27)) (justify left bottom) hide)
    )
    (property "Dielectric" "" (at 42.545 125.095 0)
      (effects (font (size 1.27 1.27)) (justify left bottom) hide)
    )
    (pin "1")
    (pin "2")
    (instances
      (project "data-center-rdimm-ddr4-tester"
        (path ""
          (reference "C47") (unit 1)
        )
      )
    )
  )

  (symbol (lib_id "antmicropower:GND") (at 73.025 109.855 0) (mirror y) (unit 1)
    (in_bom yes) (on_board yes) (dnp no) (fields_autoplaced)
    (property "Reference" "#PWR0116" (at 73.025 116.205 0)
      (effects (font (size 1.27 1.27)) hide)
    )
    (property "Value" "GND" (at 73.025 114.3 0)
      (effects (font (size 1.27 1.27)))
    )
    (property "Footprint" "" (at 73.025 109.855 0)
      (effects (font (size 1.27 1.27)) hide)
    )
    (property "Datasheet" "" (at 73.025 109.855 0)
      (effects (font (size 1.27 1.27)) hide)
    )
    (property "Author" "Antmicro" (at 64.135 117.475 0)
      (effects (font (size 1.27 1.27) (thickness 0.15)) (justify left bottom) hide)
    )
    (property "License" "Apache-2.0" (at 64.135 120.015 0)
      (effects (font (size 1.27 1.27) (thickness 0.15)) (justify left bottom) hide)
    )
    (pin "1")
    (instances
      (project "data-center-rdimm-ddr4-tester"
        (path ""
          (reference "#PWR0116") (unit 1)
        )
      )
    )
  )

  (symbol (lib_id "antmicroCapacitorsmisc:C_100n_0201") (at 80.01 104.775 270) (unit 1)
    (in_bom yes) (on_board yes) (dnp no)
    (property "Reference" "C49" (at 80.01 105.41 90)
      (effects (font (size 1.524 1.524)) (justify left))
    )
    (property "Value" "C_100n_0201" (at 69.85 125.095 0)
      (effects (font (size 1.27 1.27) (thickness 0.15)) (justify left bottom) hide)
    )
    (property "Footprint" "antmicro-footprints:C_0201" (at 67.31 125.095 0)
      (effects (font (size 1.27 1.27) (thickness 0.15)) (justify left bottom) hide)
    )
    (property "Datasheet" " " (at 64.77 125.095 0)
      (effects (font (size 1.27 1.27) (thickness 0.15)) (justify left bottom) hide)
    )
    (property "Manufacturer" "Yaego" (at 59.69 125.095 0)
      (effects (font (size 1.27 1.27) (thickness 0.15)) (justify left bottom) hide)
    )
    (property "MPN" "CC0201KRX6S5BB104" (at 62.23 125.095 0)
      (effects (font (size 1.27 1.27) (thickness 0.15)) (justify left bottom) hide)
    )
    (property "Val" "100n" (at 80.01 109.22 90)
      (effects (font (size 1.27 1.27) (thickness 0.15)) (justify left))
    )
    (property "License" "Apache-2.0" (at 57.15 125.095 0)
      (effects (font (size 1.27 1.27) (thickness 0.15)) (justify left bottom) hide)
    )
    (property "Author" "Antmicro" (at 54.61 125.095 0)
      (effects (font (size 1.27 1.27) (thickness 0.15)) (justify left bottom) hide)
    )
    (property "Voltage" "" (at 52.07 125.095 0)
      (effects (font (size 1.27 1.27)) (justify left bottom) hide)
    )
    (property "Dielectric" "" (at 49.53 125.095 0)
      (effects (font (size 1.27 1.27)) (justify left bottom) hide)
    )
    (pin "1")
    (pin "2")
    (instances
      (project "data-center-rdimm-ddr4-tester"
        (path ""
          (reference "C49") (unit 1)
        )
      )
    )
  )

  (symbol (lib_id "antmicropower:GND") (at 80.01 109.855 0) (mirror y) (unit 1)
    (in_bom yes) (on_board yes) (dnp no) (fields_autoplaced)
    (property "Reference" "#PWR0122" (at 80.01 116.205 0)
      (effects (font (size 1.27 1.27)) hide)
    )
    (property "Value" "GND" (at 80.01 114.3 0)
      (effects (font (size 1.27 1.27)))
    )
    (property "Footprint" "" (at 80.01 109.855 0)
      (effects (font (size 1.27 1.27)) hide)
    )
    (property "Datasheet" "" (at 80.01 109.855 0)
      (effects (font (size 1.27 1.27)) hide)
    )
    (property "Author" "Antmicro" (at 71.12 117.475 0)
      (effects (font (size 1.27 1.27) (thickness 0.15)) (justify left bottom) hide)
    )
    (property "License" "Apache-2.0" (at 71.12 120.015 0)
      (effects (font (size 1.27 1.27) (thickness 0.15)) (justify left bottom) hide)
    )
    (pin "1")
    (instances
      (project "data-center-rdimm-ddr4-tester"
        (path ""
          (reference "#PWR0122") (unit 1)
        )
      )
    )
  )

  (symbol (lib_id "antmicroCapacitorsmisc:C_100n_0201") (at 86.995 104.775 270) (unit 1)
    (in_bom yes) (on_board yes) (dnp no)
    (property "Reference" "C51" (at 86.995 105.41 90)
      (effects (font (size 1.524 1.524)) (justify left))
    )
    (property "Value" "C_100n_0201" (at 76.835 125.095 0)
      (effects (font (size 1.27 1.27) (thickness 0.15)) (justify left bottom) hide)
    )
    (property "Footprint" "antmicro-footprints:C_0201" (at 74.295 125.095 0)
      (effects (font (size 1.27 1.27) (thickness 0.15)) (justify left bottom) hide)
    )
    (property "Datasheet" " " (at 71.755 125.095 0)
      (effects (font (size 1.27 1.27) (thickness 0.15)) (justify left bottom) hide)
    )
    (property "Manufacturer" "Yaego" (at 66.675 125.095 0)
      (effects (font (size 1.27 1.27) (thickness 0.15)) (justify left bottom) hide)
    )
    (property "MPN" "CC0201KRX6S5BB104" (at 69.215 125.095 0)
      (effects (font (size 1.27 1.27) (thickness 0.15)) (justify left bottom) hide)
    )
    (property "Val" "100n" (at 86.995 109.22 90)
      (effects (font (size 1.27 1.27) (thickness 0.15)) (justify left))
    )
    (property "License" "Apache-2.0" (at 64.135 125.095 0)
      (effects (font (size 1.27 1.27) (thickness 0.15)) (justify left bottom) hide)
    )
    (property "Author" "Antmicro" (at 61.595 125.095 0)
      (effects (font (size 1.27 1.27) (thickness 0.15)) (justify left bottom) hide)
    )
    (property "Voltage" "" (at 59.055 125.095 0)
      (effects (font (size 1.27 1.27)) (justify left bottom) hide)
    )
    (property "Dielectric" "" (at 56.515 125.095 0)
      (effects (font (size 1.27 1.27)) (justify left bottom) hide)
    )
    (pin "1")
    (pin "2")
    (instances
      (project "data-center-rdimm-ddr4-tester"
        (path ""
          (reference "C51") (unit 1)
        )
      )
    )
  )

  (symbol (lib_id "antmicropower:GND") (at 86.995 109.855 0) (mirror y) (unit 1)
    (in_bom yes) (on_board yes) (dnp no) (fields_autoplaced)
    (property "Reference" "#PWR0123" (at 86.995 116.205 0)
      (effects (font (size 1.27 1.27)) hide)
    )
    (property "Value" "GND" (at 86.995 114.3 0)
      (effects (font (size 1.27 1.27)))
    )
    (property "Footprint" "" (at 86.995 109.855 0)
      (effects (font (size 1.27 1.27)) hide)
    )
    (property "Datasheet" "" (at 86.995 109.855 0)
      (effects (font (size 1.27 1.27)) hide)
    )
    (property "Author" "Antmicro" (at 78.105 117.475 0)
      (effects (font (size 1.27 1.27) (thickness 0.15)) (justify left bottom) hide)
    )
    (property "License" "Apache-2.0" (at 78.105 120.015 0)
      (effects (font (size 1.27 1.27) (thickness 0.15)) (justify left bottom) hide)
    )
    (pin "1")
    (instances
      (project "data-center-rdimm-ddr4-tester"
        (path ""
          (reference "#PWR0123") (unit 1)
        )
      )
    )
  )

  (symbol (lib_id "antmicroCapacitorsmisc:C_100n_0201") (at 93.98 104.775 270) (unit 1)
    (in_bom yes) (on_board yes) (dnp no)
    (property "Reference" "C53" (at 93.98 105.41 90)
      (effects (font (size 1.524 1.524)) (justify left))
    )
    (property "Value" "C_100n_0201" (at 83.82 125.095 0)
      (effects (font (size 1.27 1.27) (thickness 0.15)) (justify left bottom) hide)
    )
    (property "Footprint" "antmicro-footprints:C_0201" (at 81.28 125.095 0)
      (effects (font (size 1.27 1.27) (thickness 0.15)) (justify left bottom) hide)
    )
    (property "Datasheet" " " (at 78.74 125.095 0)
      (effects (font (size 1.27 1.27) (thickness 0.15)) (justify left bottom) hide)
    )
    (property "Manufacturer" "Yaego" (at 73.66 125.095 0)
      (effects (font (size 1.27 1.27) (thickness 0.15)) (justify left bottom) hide)
    )
    (property "MPN" "CC0201KRX6S5BB104" (at 76.2 125.095 0)
      (effects (font (size 1.27 1.27) (thickness 0.15)) (justify left bottom) hide)
    )
    (property "Val" "100n" (at 93.98 109.22 90)
      (effects (font (size 1.27 1.27) (thickness 0.15)) (justify left))
    )
    (property "License" "Apache-2.0" (at 71.12 125.095 0)
      (effects (font (size 1.27 1.27) (thickness 0.15)) (justify left bottom) hide)
    )
    (property "Author" "Antmicro" (at 68.58 125.095 0)
      (effects (font (size 1.27 1.27) (thickness 0.15)) (justify left bottom) hide)
    )
    (property "Voltage" "" (at 66.04 125.095 0)
      (effects (font (size 1.27 1.27)) (justify left bottom) hide)
    )
    (property "Dielectric" "" (at 63.5 125.095 0)
      (effects (font (size 1.27 1.27)) (justify left bottom) hide)
    )
    (pin "1")
    (pin "2")
    (instances
      (project "data-center-rdimm-ddr4-tester"
        (path ""
          (reference "C53") (unit 1)
        )
      )
    )
  )

  (symbol (lib_id "antmicropower:GND") (at 93.98 109.855 0) (mirror y) (unit 1)
    (in_bom yes) (on_board yes) (dnp no) (fields_autoplaced)
    (property "Reference" "#PWR0172" (at 93.98 116.205 0)
      (effects (font (size 1.27 1.27)) hide)
    )
    (property "Value" "GND" (at 93.98 114.3 0)
      (effects (font (size 1.27 1.27)))
    )
    (property "Footprint" "" (at 93.98 109.855 0)
      (effects (font (size 1.27 1.27)) hide)
    )
    (property "Datasheet" "" (at 93.98 109.855 0)
      (effects (font (size 1.27 1.27)) hide)
    )
    (property "Author" "Antmicro" (at 85.09 117.475 0)
      (effects (font (size 1.27 1.27) (thickness 0.15)) (justify left bottom) hide)
    )
    (property "License" "Apache-2.0" (at 85.09 120.015 0)
      (effects (font (size 1.27 1.27) (thickness 0.15)) (justify left bottom) hide)
    )
    (pin "1")
    (instances
      (project "data-center-rdimm-ddr4-tester"
        (path ""
          (reference "#PWR0172") (unit 1)
        )
      )
    )
  )

  (symbol (lib_id "antmicroCapacitorsmisc:C_100n_0201") (at 100.965 104.775 270) (unit 1)
    (in_bom yes) (on_board yes) (dnp no)
    (property "Reference" "C55" (at 100.965 105.41 90)
      (effects (font (size 1.524 1.524)) (justify left))
    )
    (property "Value" "C_100n_0201" (at 90.805 125.095 0)
      (effects (font (size 1.27 1.27) (thickness 0.15)) (justify left bottom) hide)
    )
    (property "Footprint" "antmicro-footprints:C_0201" (at 88.265 125.095 0)
      (effects (font (size 1.27 1.27) (thickness 0.15)) (justify left bottom) hide)
    )
    (property "Datasheet" " " (at 85.725 125.095 0)
      (effects (font (size 1.27 1.27) (thickness 0.15)) (justify left bottom) hide)
    )
    (property "Manufacturer" "Yaego" (at 80.645 125.095 0)
      (effects (font (size 1.27 1.27) (thickness 0.15)) (justify left bottom) hide)
    )
    (property "MPN" "CC0201KRX6S5BB104" (at 83.185 125.095 0)
      (effects (font (size 1.27 1.27) (thickness 0.15)) (justify left bottom) hide)
    )
    (property "Val" "100n" (at 100.965 109.22 90)
      (effects (font (size 1.27 1.27) (thickness 0.15)) (justify left))
    )
    (property "License" "Apache-2.0" (at 78.105 125.095 0)
      (effects (font (size 1.27 1.27) (thickness 0.15)) (justify left bottom) hide)
    )
    (property "Author" "Antmicro" (at 75.565 125.095 0)
      (effects (font (size 1.27 1.27) (thickness 0.15)) (justify left bottom) hide)
    )
    (property "Voltage" "" (at 73.025 125.095 0)
      (effects (font (size 1.27 1.27)) (justify left bottom) hide)
    )
    (property "Dielectric" "" (at 70.485 125.095 0)
      (effects (font (size 1.27 1.27)) (justify left bottom) hide)
    )
    (pin "1")
    (pin "2")
    (instances
      (project "data-center-rdimm-ddr4-tester"
        (path ""
          (reference "C55") (unit 1)
        )
      )
    )
  )

  (symbol (lib_id "antmicropower:GND") (at 100.965 109.855 0) (mirror y) (unit 1)
    (in_bom yes) (on_board yes) (dnp no) (fields_autoplaced)
    (property "Reference" "#PWR0173" (at 100.965 116.205 0)
      (effects (font (size 1.27 1.27)) hide)
    )
    (property "Value" "GND" (at 100.965 114.3 0)
      (effects (font (size 1.27 1.27)))
    )
    (property "Footprint" "" (at 100.965 109.855 0)
      (effects (font (size 1.27 1.27)) hide)
    )
    (property "Datasheet" "" (at 100.965 109.855 0)
      (effects (font (size 1.27 1.27)) hide)
    )
    (property "Author" "Antmicro" (at 92.075 117.475 0)
      (effects (font (size 1.27 1.27) (thickness 0.15)) (justify left bottom) hide)
    )
    (property "License" "Apache-2.0" (at 92.075 120.015 0)
      (effects (font (size 1.27 1.27) (thickness 0.15)) (justify left bottom) hide)
    )
    (pin "1")
    (instances
      (project "data-center-rdimm-ddr4-tester"
        (path ""
          (reference "#PWR0173") (unit 1)
        )
      )
    )
  )

  (symbol (lib_id "antmicropower:GND") (at 95.885 206.375 0) (unit 1)
    (in_bom yes) (on_board yes) (dnp no) (fields_autoplaced)
    (property "Reference" "#PWR0252" (at 95.885 212.725 0)
      (effects (font (size 1.27 1.27)) hide)
    )
    (property "Value" "GND" (at 95.885 211.455 0)
      (effects (font (size 1.27 1.27)))
    )
    (property "Footprint" "" (at 95.885 206.375 0)
      (effects (font (size 1.27 1.27)) hide)
    )
    (property "Datasheet" "" (at 95.885 206.375 0)
      (effects (font (size 1.27 1.27)) hide)
    )
    (property "Author" "Antmicro" (at 104.775 213.995 0)
      (effects (font (size 1.27 1.27) (thickness 0.15)) (justify left bottom) hide)
    )
    (property "License" "Apache-2.0" (at 104.775 216.535 0)
      (effects (font (size 1.27 1.27) (thickness 0.15)) (justify left bottom) hide)
    )
    (pin "1")
    (instances
      (project "data-center-rdimm-ddr4-tester"
        (path ""
          (reference "#PWR0252") (unit 1)
        )
      )
    )
  )

  (symbol (lib_id "antmicroCapacitors0603:C_47u_0603") (at 36.195 201.295 270) (unit 1)
    (in_bom yes) (on_board yes) (dnp no)
    (property "Reference" "C3" (at 36.195 201.93 90)
      (effects (font (size 1.524 1.524)) (justify left))
    )
    (property "Value" "C_47u_0603" (at 26.035 221.615 0)
      (effects (font (size 1.27 1.27) (thickness 0.15)) (justify left bottom) hide)
    )
    (property "Footprint" "antmicro-footprints:C_0603_1608Metric" (at 23.495 221.615 0)
      (effects (font (size 1.27 1.27) (thickness 0.15)) (justify left bottom) hide)
    )
    (property "Datasheet" " " (at 20.955 221.615 0)
      (effects (font (size 1.27 1.27) (thickness 0.15)) (justify left bottom) hide)
    )
    (property "Manufacturer" "Murata" (at 15.875 221.615 0)
      (effects (font (size 1.27 1.27) (thickness 0.15)) (justify left bottom) hide)
    )
    (property "MPN" "GRM188R60J476ME15D" (at 18.415 221.615 0)
      (effects (font (size 1.27 1.27) (thickness 0.15)) (justify left bottom) hide)
    )
    (property "Val" "47u" (at 36.195 205.74 90)
      (effects (font (size 1.27 1.27) (thickness 0.15)) (justify left))
    )
    (property "License" "Apache-2.0" (at 13.335 221.615 0)
      (effects (font (size 1.27 1.27) (thickness 0.15)) (justify left bottom) hide)
    )
    (property "Author" "Antmicro" (at 10.795 221.615 0)
      (effects (font (size 1.27 1.27) (thickness 0.15)) (justify left bottom) hide)
    )
    (property "Voltage" "" (at 8.255 221.615 0)
      (effects (font (size 1.27 1.27)) (justify left bottom) hide)
    )
    (property "Dielectric" "" (at 5.715 221.615 0)
      (effects (font (size 1.27 1.27)) (justify left bottom) hide)
    )
    (pin "1")
    (pin "2")
    (instances
      (project "data-center-rdimm-ddr4-tester"
        (path ""
          (reference "C3") (unit 1)
        )
      )
    )
  )

  (symbol (lib_id "antmicroCapacitors0603:C_47u_0603") (at 42.545 201.295 270) (unit 1)
    (in_bom yes) (on_board yes) (dnp no)
    (property "Reference" "C6" (at 42.545 201.93 90)
      (effects (font (size 1.524 1.524)) (justify left))
    )
    (property "Value" "C_47u_0603" (at 32.385 221.615 0)
      (effects (font (size 1.27 1.27) (thickness 0.15)) (justify left bottom) hide)
    )
    (property "Footprint" "antmicro-footprints:C_0603_1608Metric" (at 29.845 221.615 0)
      (effects (font (size 1.27 1.27) (thickness 0.15)) (justify left bottom) hide)
    )
    (property "Datasheet" " " (at 27.305 221.615 0)
      (effects (font (size 1.27 1.27) (thickness 0.15)) (justify left bottom) hide)
    )
    (property "Manufacturer" "Murata" (at 22.225 221.615 0)
      (effects (font (size 1.27 1.27) (thickness 0.15)) (justify left bottom) hide)
    )
    (property "MPN" "GRM188R60J476ME15D" (at 24.765 221.615 0)
      (effects (font (size 1.27 1.27) (thickness 0.15)) (justify left bottom) hide)
    )
    (property "Val" "47u" (at 42.545 205.74 90)
      (effects (font (size 1.27 1.27) (thickness 0.15)) (justify left))
    )
    (property "License" "Apache-2.0" (at 19.685 221.615 0)
      (effects (font (size 1.27 1.27) (thickness 0.15)) (justify left bottom) hide)
    )
    (property "Author" "Antmicro" (at 17.145 221.615 0)
      (effects (font (size 1.27 1.27) (thickness 0.15)) (justify left bottom) hide)
    )
    (property "Voltage" "" (at 14.605 221.615 0)
      (effects (font (size 1.27 1.27)) (justify left bottom) hide)
    )
    (property "Dielectric" "" (at 12.065 221.615 0)
      (effects (font (size 1.27 1.27)) (justify left bottom) hide)
    )
    (pin "1")
    (pin "2")
    (instances
      (project "data-center-rdimm-ddr4-tester"
        (path ""
          (reference "C6") (unit 1)
        )
      )
    )
  )

  (symbol (lib_id "antmicroCapacitors0603:C_47u_0603") (at 49.53 201.295 270) (unit 1)
    (in_bom yes) (on_board yes) (dnp no)
    (property "Reference" "C15" (at 49.53 201.93 90)
      (effects (font (size 1.524 1.524)) (justify left))
    )
    (property "Value" "C_47u_0603" (at 39.37 221.615 0)
      (effects (font (size 1.27 1.27) (thickness 0.15)) (justify left bottom) hide)
    )
    (property "Footprint" "antmicro-footprints:C_0603_1608Metric" (at 36.83 221.615 0)
      (effects (font (size 1.27 1.27) (thickness 0.15)) (justify left bottom) hide)
    )
    (property "Datasheet" " " (at 34.29 221.615 0)
      (effects (font (size 1.27 1.27) (thickness 0.15)) (justify left bottom) hide)
    )
    (property "Manufacturer" "Murata" (at 29.21 221.615 0)
      (effects (font (size 1.27 1.27) (thickness 0.15)) (justify left bottom) hide)
    )
    (property "MPN" "GRM188R60J476ME15D" (at 31.75 221.615 0)
      (effects (font (size 1.27 1.27) (thickness 0.15)) (justify left bottom) hide)
    )
    (property "Val" "47u" (at 49.53 205.74 90)
      (effects (font (size 1.27 1.27) (thickness 0.15)) (justify left))
    )
    (property "License" "Apache-2.0" (at 26.67 221.615 0)
      (effects (font (size 1.27 1.27) (thickness 0.15)) (justify left bottom) hide)
    )
    (property "Author" "Antmicro" (at 24.13 221.615 0)
      (effects (font (size 1.27 1.27) (thickness 0.15)) (justify left bottom) hide)
    )
    (property "Voltage" "" (at 21.59 221.615 0)
      (effects (font (size 1.27 1.27)) (justify left bottom) hide)
    )
    (property "Dielectric" "" (at 19.05 221.615 0)
      (effects (font (size 1.27 1.27)) (justify left bottom) hide)
    )
    (pin "1")
    (pin "2")
    (instances
      (project "data-center-rdimm-ddr4-tester"
        (path ""
          (reference "C15") (unit 1)
        )
      )
    )
  )

  (symbol (lib_id "antmicroCapacitors0603:C_47u_0603") (at 44.45 135.255 270) (unit 1)
    (in_bom yes) (on_board yes) (dnp no)
    (property "Reference" "C23" (at 44.45 135.89 90)
      (effects (font (size 1.524 1.524)) (justify left))
    )
    (property "Value" "C_47u_0603" (at 34.29 155.575 0)
      (effects (font (size 1.27 1.27) (thickness 0.15)) (justify left bottom) hide)
    )
    (property "Footprint" "antmicro-footprints:C_0603_1608Metric" (at 31.75 155.575 0)
      (effects (font (size 1.27 1.27) (thickness 0.15)) (justify left bottom) hide)
    )
    (property "Datasheet" " " (at 29.21 155.575 0)
      (effects (font (size 1.27 1.27) (thickness 0.15)) (justify left bottom) hide)
    )
    (property "Manufacturer" "Murata" (at 24.13 155.575 0)
      (effects (font (size 1.27 1.27) (thickness 0.15)) (justify left bottom) hide)
    )
    (property "MPN" "GRM188R60J476ME15D" (at 26.67 155.575 0)
      (effects (font (size 1.27 1.27) (thickness 0.15)) (justify left bottom) hide)
    )
    (property "Val" "47u" (at 44.45 139.7 90)
      (effects (font (size 1.27 1.27) (thickness 0.15)) (justify left))
    )
    (property "License" "Apache-2.0" (at 21.59 155.575 0)
      (effects (font (size 1.27 1.27) (thickness 0.15)) (justify left bottom) hide)
    )
    (property "Author" "Antmicro" (at 19.05 155.575 0)
      (effects (font (size 1.27 1.27) (thickness 0.15)) (justify left bottom) hide)
    )
    (property "Voltage" "" (at 16.51 155.575 0)
      (effects (font (size 1.27 1.27)) (justify left bottom) hide)
    )
    (property "Dielectric" "" (at 13.97 155.575 0)
      (effects (font (size 1.27 1.27)) (justify left bottom) hide)
    )
    (pin "1")
    (pin "2")
    (instances
      (project "data-center-rdimm-ddr4-tester"
        (path ""
          (reference "C23") (unit 1)
        )
      )
    )
  )

  (symbol (lib_id "antmicroCapacitors0603:C_47u_0603") (at 51.435 135.255 270) (unit 1)
    (in_bom yes) (on_board yes) (dnp no)
    (property "Reference" "C24" (at 51.435 135.89 90)
      (effects (font (size 1.524 1.524)) (justify left))
    )
    (property "Value" "C_47u_0603" (at 41.275 155.575 0)
      (effects (font (size 1.27 1.27) (thickness 0.15)) (justify left bottom) hide)
    )
    (property "Footprint" "antmicro-footprints:C_0603_1608Metric" (at 38.735 155.575 0)
      (effects (font (size 1.27 1.27) (thickness 0.15)) (justify left bottom) hide)
    )
    (property "Datasheet" " " (at 36.195 155.575 0)
      (effects (font (size 1.27 1.27) (thickness 0.15)) (justify left bottom) hide)
    )
    (property "Manufacturer" "Murata" (at 31.115 155.575 0)
      (effects (font (size 1.27 1.27) (thickness 0.15)) (justify left bottom) hide)
    )
    (property "MPN" "GRM188R60J476ME15D" (at 33.655 155.575 0)
      (effects (font (size 1.27 1.27) (thickness 0.15)) (justify left bottom) hide)
    )
    (property "Val" "47u" (at 51.435 139.7 90)
      (effects (font (size 1.27 1.27) (thickness 0.15)) (justify left))
    )
    (property "License" "Apache-2.0" (at 28.575 155.575 0)
      (effects (font (size 1.27 1.27) (thickness 0.15)) (justify left bottom) hide)
    )
    (property "Author" "Antmicro" (at 26.035 155.575 0)
      (effects (font (size 1.27 1.27) (thickness 0.15)) (justify left bottom) hide)
    )
    (property "Voltage" "" (at 23.495 155.575 0)
      (effects (font (size 1.27 1.27)) (justify left bottom) hide)
    )
    (property "Dielectric" "" (at 20.955 155.575 0)
      (effects (font (size 1.27 1.27)) (justify left bottom) hide)
    )
    (pin "1")
    (pin "2")
    (instances
      (project "data-center-rdimm-ddr4-tester"
        (path ""
          (reference "C24") (unit 1)
        )
      )
    )
  )

  (symbol (lib_id "antmicropower:GND") (at 36.195 206.375 0) (unit 1)
    (in_bom yes) (on_board yes) (dnp no) (fields_autoplaced)
    (property "Reference" "#PWR0125" (at 36.195 212.725 0)
      (effects (font (size 1.27 1.27)) hide)
    )
    (property "Value" "GND" (at 36.195 210.82 0)
      (effects (font (size 1.27 1.27)))
    )
    (property "Footprint" "" (at 36.195 206.375 0)
      (effects (font (size 1.27 1.27)) hide)
    )
    (property "Datasheet" "" (at 36.195 206.375 0)
      (effects (font (size 1.27 1.27)) hide)
    )
    (property "Author" "Antmicro" (at 45.085 213.995 0)
      (effects (font (size 1.27 1.27) (thickness 0.15)) (justify left bottom) hide)
    )
    (property "License" "Apache-2.0" (at 45.085 216.535 0)
      (effects (font (size 1.27 1.27) (thickness 0.15)) (justify left bottom) hide)
    )
    (pin "1")
    (instances
      (project "data-center-rdimm-ddr4-tester"
        (path ""
          (reference "#PWR0125") (unit 1)
        )
      )
    )
  )

  (symbol (lib_id "antmicropower:GND") (at 42.545 206.375 0) (unit 1)
    (in_bom yes) (on_board yes) (dnp no) (fields_autoplaced)
    (property "Reference" "#PWR0126" (at 42.545 212.725 0)
      (effects (font (size 1.27 1.27)) hide)
    )
    (property "Value" "GND" (at 42.545 210.82 0)
      (effects (font (size 1.27 1.27)))
    )
    (property "Footprint" "" (at 42.545 206.375 0)
      (effects (font (size 1.27 1.27)) hide)
    )
    (property "Datasheet" "" (at 42.545 206.375 0)
      (effects (font (size 1.27 1.27)) hide)
    )
    (property "Author" "Antmicro" (at 51.435 213.995 0)
      (effects (font (size 1.27 1.27) (thickness 0.15)) (justify left bottom) hide)
    )
    (property "License" "Apache-2.0" (at 51.435 216.535 0)
      (effects (font (size 1.27 1.27) (thickness 0.15)) (justify left bottom) hide)
    )
    (pin "1")
    (instances
      (project "data-center-rdimm-ddr4-tester"
        (path ""
          (reference "#PWR0126") (unit 1)
        )
      )
    )
  )

  (symbol (lib_id "antmicropower:GND") (at 49.53 206.375 0) (unit 1)
    (in_bom yes) (on_board yes) (dnp no) (fields_autoplaced)
    (property "Reference" "#PWR0127" (at 49.53 212.725 0)
      (effects (font (size 1.27 1.27)) hide)
    )
    (property "Value" "GND" (at 49.53 210.82 0)
      (effects (font (size 1.27 1.27)))
    )
    (property "Footprint" "" (at 49.53 206.375 0)
      (effects (font (size 1.27 1.27)) hide)
    )
    (property "Datasheet" "" (at 49.53 206.375 0)
      (effects (font (size 1.27 1.27)) hide)
    )
    (property "Author" "Antmicro" (at 58.42 213.995 0)
      (effects (font (size 1.27 1.27) (thickness 0.15)) (justify left bottom) hide)
    )
    (property "License" "Apache-2.0" (at 58.42 216.535 0)
      (effects (font (size 1.27 1.27) (thickness 0.15)) (justify left bottom) hide)
    )
    (pin "1")
    (instances
      (project "data-center-rdimm-ddr4-tester"
        (path ""
          (reference "#PWR0127") (unit 1)
        )
      )
    )
  )

  (symbol (lib_id "antmicropower:GND") (at 44.45 140.335 0) (unit 1)
    (in_bom yes) (on_board yes) (dnp no) (fields_autoplaced)
    (property "Reference" "#PWR0130" (at 44.45 146.685 0)
      (effects (font (size 1.27 1.27)) hide)
    )
    (property "Value" "GND" (at 44.45 144.78 0)
      (effects (font (size 1.27 1.27)))
    )
    (property "Footprint" "" (at 44.45 140.335 0)
      (effects (font (size 1.27 1.27)) hide)
    )
    (property "Datasheet" "" (at 44.45 140.335 0)
      (effects (font (size 1.27 1.27)) hide)
    )
    (property "Author" "Antmicro" (at 53.34 147.955 0)
      (effects (font (size 1.27 1.27) (thickness 0.15)) (justify left bottom) hide)
    )
    (property "License" "Apache-2.0" (at 53.34 150.495 0)
      (effects (font (size 1.27 1.27) (thickness 0.15)) (justify left bottom) hide)
    )
    (pin "1")
    (instances
      (project "data-center-rdimm-ddr4-tester"
        (path ""
          (reference "#PWR0130") (unit 1)
        )
      )
    )
  )

  (symbol (lib_id "antmicropower:GND") (at 51.435 140.335 0) (unit 1)
    (in_bom yes) (on_board yes) (dnp no) (fields_autoplaced)
    (property "Reference" "#PWR0131" (at 51.435 146.685 0)
      (effects (font (size 1.27 1.27)) hide)
    )
    (property "Value" "GND" (at 51.435 144.78 0)
      (effects (font (size 1.27 1.27)))
    )
    (property "Footprint" "" (at 51.435 140.335 0)
      (effects (font (size 1.27 1.27)) hide)
    )
    (property "Datasheet" "" (at 51.435 140.335 0)
      (effects (font (size 1.27 1.27)) hide)
    )
    (property "Author" "Antmicro" (at 60.325 147.955 0)
      (effects (font (size 1.27 1.27) (thickness 0.15)) (justify left bottom) hide)
    )
    (property "License" "Apache-2.0" (at 60.325 150.495 0)
      (effects (font (size 1.27 1.27) (thickness 0.15)) (justify left bottom) hide)
    )
    (pin "1")
    (instances
      (project "data-center-rdimm-ddr4-tester"
        (path ""
          (reference "#PWR0131") (unit 1)
        )
      )
    )
  )

  (symbol (lib_id "antmicroCapacitorsmisc:C_100n_0201") (at 31.115 66.04 270) (unit 1)
    (in_bom yes) (on_board yes) (dnp no)
    (property "Reference" "C57" (at 31.115 66.675 90)
      (effects (font (size 1.524 1.524)) (justify left))
    )
    (property "Value" "C_100n_0201" (at 20.955 86.36 0)
      (effects (font (size 1.27 1.27) (thickness 0.15)) (justify left bottom) hide)
    )
    (property "Footprint" "antmicro-footprints:C_0201" (at 18.415 86.36 0)
      (effects (font (size 1.27 1.27) (thickness 0.15)) (justify left bottom) hide)
    )
    (property "Datasheet" " " (at 15.875 86.36 0)
      (effects (font (size 1.27 1.27) (thickness 0.15)) (justify left bottom) hide)
    )
    (property "Manufacturer" "Yaego" (at 10.795 86.36 0)
      (effects (font (size 1.27 1.27) (thickness 0.15)) (justify left bottom) hide)
    )
    (property "MPN" "CC0201KRX6S5BB104" (at 13.335 86.36 0)
      (effects (font (size 1.27 1.27) (thickness 0.15)) (justify left bottom) hide)
    )
    (property "Val" "100n" (at 31.115 70.485 90)
      (effects (font (size 1.27 1.27) (thickness 0.15)) (justify left))
    )
    (property "License" "Apache-2.0" (at 8.255 86.36 0)
      (effects (font (size 1.27 1.27) (thickness 0.15)) (justify left bottom) hide)
    )
    (property "Author" "Antmicro" (at 5.715 86.36 0)
      (effects (font (size 1.27 1.27) (thickness 0.15)) (justify left bottom) hide)
    )
    (property "Voltage" "" (at 3.175 86.36 0)
      (effects (font (size 1.27 1.27)) (justify left bottom) hide)
    )
    (property "Dielectric" "" (at 0.635 86.36 0)
      (effects (font (size 1.27 1.27)) (justify left bottom) hide)
    )
    (pin "1")
    (pin "2")
    (instances
      (project "data-center-rdimm-ddr4-tester"
        (path ""
          (reference "C57") (unit 1)
        )
      )
    )
  )

  (symbol (lib_id "antmicropower:GND") (at 31.115 71.12 0) (mirror y) (unit 1)
    (in_bom yes) (on_board yes) (dnp no) (fields_autoplaced)
    (property "Reference" "#PWR0174" (at 31.115 77.47 0)
      (effects (font (size 1.27 1.27)) hide)
    )
    (property "Value" "GND" (at 31.115 76.2 0)
      (effects (font (size 1.27 1.27)))
    )
    (property "Footprint" "" (at 31.115 71.12 0)
      (effects (font (size 1.27 1.27)) hide)
    )
    (property "Datasheet" "" (at 31.115 71.12 0)
      (effects (font (size 1.27 1.27)) hide)
    )
    (property "Author" "Antmicro" (at 22.225 78.74 0)
      (effects (font (size 1.27 1.27) (thickness 0.15)) (justify left bottom) hide)
    )
    (property "License" "Apache-2.0" (at 22.225 81.28 0)
      (effects (font (size 1.27 1.27) (thickness 0.15)) (justify left bottom) hide)
    )
    (pin "1")
    (instances
      (project "data-center-rdimm-ddr4-tester"
        (path ""
          (reference "#PWR0174") (unit 1)
        )
      )
    )
  )

  (symbol (lib_id "antmicroCapacitorsmisc:C_100n_0201") (at 38.1 66.04 270) (unit 1)
    (in_bom yes) (on_board yes) (dnp no)
    (property "Reference" "C58" (at 38.1 66.675 90)
      (effects (font (size 1.524 1.524)) (justify left))
    )
    (property "Value" "C_100n_0201" (at 27.94 86.36 0)
      (effects (font (size 1.27 1.27) (thickness 0.15)) (justify left bottom) hide)
    )
    (property "Footprint" "antmicro-footprints:C_0201" (at 25.4 86.36 0)
      (effects (font (size 1.27 1.27) (thickness 0.15)) (justify left bottom) hide)
    )
    (property "Datasheet" " " (at 22.86 86.36 0)
      (effects (font (size 1.27 1.27) (thickness 0.15)) (justify left bottom) hide)
    )
    (property "Manufacturer" "Yaego" (at 17.78 86.36 0)
      (effects (font (size 1.27 1.27) (thickness 0.15)) (justify left bottom) hide)
    )
    (property "MPN" "CC0201KRX6S5BB104" (at 20.32 86.36 0)
      (effects (font (size 1.27 1.27) (thickness 0.15)) (justify left bottom) hide)
    )
    (property "Val" "100n" (at 38.1 70.485 90)
      (effects (font (size 1.27 1.27) (thickness 0.15)) (justify left))
    )
    (property "License" "Apache-2.0" (at 15.24 86.36 0)
      (effects (font (size 1.27 1.27) (thickness 0.15)) (justify left bottom) hide)
    )
    (property "Author" "Antmicro" (at 12.7 86.36 0)
      (effects (font (size 1.27 1.27) (thickness 0.15)) (justify left bottom) hide)
    )
    (property "Voltage" "" (at 10.16 86.36 0)
      (effects (font (size 1.27 1.27)) (justify left bottom) hide)
    )
    (property "Dielectric" "" (at 7.62 86.36 0)
      (effects (font (size 1.27 1.27)) (justify left bottom) hide)
    )
    (pin "1")
    (pin "2")
    (instances
      (project "data-center-rdimm-ddr4-tester"
        (path ""
          (reference "C58") (unit 1)
        )
      )
    )
  )

  (symbol (lib_id "antmicropower:GND") (at 38.1 71.12 0) (mirror y) (unit 1)
    (in_bom yes) (on_board yes) (dnp no) (fields_autoplaced)
    (property "Reference" "#PWR0175" (at 38.1 77.47 0)
      (effects (font (size 1.27 1.27)) hide)
    )
    (property "Value" "GND" (at 38.1 76.2 0)
      (effects (font (size 1.27 1.27)))
    )
    (property "Footprint" "" (at 38.1 71.12 0)
      (effects (font (size 1.27 1.27)) hide)
    )
    (property "Datasheet" "" (at 38.1 71.12 0)
      (effects (font (size 1.27 1.27)) hide)
    )
    (property "Author" "Antmicro" (at 29.21 78.74 0)
      (effects (font (size 1.27 1.27) (thickness 0.15)) (justify left bottom) hide)
    )
    (property "License" "Apache-2.0" (at 29.21 81.28 0)
      (effects (font (size 1.27 1.27) (thickness 0.15)) (justify left bottom) hide)
    )
    (pin "1")
    (instances
      (project "data-center-rdimm-ddr4-tester"
        (path ""
          (reference "#PWR0175") (unit 1)
        )
      )
    )
  )

  (symbol (lib_id "antmicroCapacitorsmisc:C_100n_0201") (at 45.085 66.04 270) (unit 1)
    (in_bom yes) (on_board yes) (dnp no)
    (property "Reference" "C59" (at 45.085 66.675 90)
      (effects (font (size 1.524 1.524)) (justify left))
    )
    (property "Value" "C_100n_0201" (at 34.925 86.36 0)
      (effects (font (size 1.27 1.27) (thickness 0.15)) (justify left bottom) hide)
    )
    (property "Footprint" "antmicro-footprints:C_0201" (at 32.385 86.36 0)
      (effects (font (size 1.27 1.27) (thickness 0.15)) (justify left bottom) hide)
    )
    (property "Datasheet" " " (at 29.845 86.36 0)
      (effects (font (size 1.27 1.27) (thickness 0.15)) (justify left bottom) hide)
    )
    (property "Manufacturer" "Yaego" (at 24.765 86.36 0)
      (effects (font (size 1.27 1.27) (thickness 0.15)) (justify left bottom) hide)
    )
    (property "MPN" "CC0201KRX6S5BB104" (at 27.305 86.36 0)
      (effects (font (size 1.27 1.27) (thickness 0.15)) (justify left bottom) hide)
    )
    (property "Val" "100n" (at 45.085 70.485 90)
      (effects (font (size 1.27 1.27) (thickness 0.15)) (justify left))
    )
    (property "License" "Apache-2.0" (at 22.225 86.36 0)
      (effects (font (size 1.27 1.27) (thickness 0.15)) (justify left bottom) hide)
    )
    (property "Author" "Antmicro" (at 19.685 86.36 0)
      (effects (font (size 1.27 1.27) (thickness 0.15)) (justify left bottom) hide)
    )
    (property "Voltage" "" (at 17.145 86.36 0)
      (effects (font (size 1.27 1.27)) (justify left bottom) hide)
    )
    (property "Dielectric" "" (at 14.605 86.36 0)
      (effects (font (size 1.27 1.27)) (justify left bottom) hide)
    )
    (pin "1")
    (pin "2")
    (instances
      (project "data-center-rdimm-ddr4-tester"
        (path ""
          (reference "C59") (unit 1)
        )
      )
    )
  )

  (symbol (lib_id "antmicropower:GND") (at 45.085 71.12 0) (mirror y) (unit 1)
    (in_bom yes) (on_board yes) (dnp no) (fields_autoplaced)
    (property "Reference" "#PWR0176" (at 45.085 77.47 0)
      (effects (font (size 1.27 1.27)) hide)
    )
    (property "Value" "GND" (at 45.085 76.2 0)
      (effects (font (size 1.27 1.27)))
    )
    (property "Footprint" "" (at 45.085 71.12 0)
      (effects (font (size 1.27 1.27)) hide)
    )
    (property "Datasheet" "" (at 45.085 71.12 0)
      (effects (font (size 1.27 1.27)) hide)
    )
    (property "Author" "Antmicro" (at 36.195 78.74 0)
      (effects (font (size 1.27 1.27) (thickness 0.15)) (justify left bottom) hide)
    )
    (property "License" "Apache-2.0" (at 36.195 81.28 0)
      (effects (font (size 1.27 1.27) (thickness 0.15)) (justify left bottom) hide)
    )
    (pin "1")
    (instances
      (project "data-center-rdimm-ddr4-tester"
        (path ""
          (reference "#PWR0176") (unit 1)
        )
      )
    )
  )

  (symbol (lib_id "antmicroCapacitorsmisc:C_100n_0201") (at 52.07 66.04 270) (unit 1)
    (in_bom yes) (on_board yes) (dnp no)
    (property "Reference" "C60" (at 52.07 66.675 90)
      (effects (font (size 1.524 1.524)) (justify left))
    )
    (property "Value" "C_100n_0201" (at 41.91 86.36 0)
      (effects (font (size 1.27 1.27) (thickness 0.15)) (justify left bottom) hide)
    )
    (property "Footprint" "antmicro-footprints:C_0201" (at 39.37 86.36 0)
      (effects (font (size 1.27 1.27) (thickness 0.15)) (justify left bottom) hide)
    )
    (property "Datasheet" " " (at 36.83 86.36 0)
      (effects (font (size 1.27 1.27) (thickness 0.15)) (justify left bottom) hide)
    )
    (property "Manufacturer" "Yaego" (at 31.75 86.36 0)
      (effects (font (size 1.27 1.27) (thickness 0.15)) (justify left bottom) hide)
    )
    (property "MPN" "CC0201KRX6S5BB104" (at 34.29 86.36 0)
      (effects (font (size 1.27 1.27) (thickness 0.15)) (justify left bottom) hide)
    )
    (property "Val" "100n" (at 52.07 70.485 90)
      (effects (font (size 1.27 1.27) (thickness 0.15)) (justify left))
    )
    (property "License" "Apache-2.0" (at 29.21 86.36 0)
      (effects (font (size 1.27 1.27) (thickness 0.15)) (justify left bottom) hide)
    )
    (property "Author" "Antmicro" (at 26.67 86.36 0)
      (effects (font (size 1.27 1.27) (thickness 0.15)) (justify left bottom) hide)
    )
    (property "Voltage" "" (at 24.13 86.36 0)
      (effects (font (size 1.27 1.27)) (justify left bottom) hide)
    )
    (property "Dielectric" "" (at 21.59 86.36 0)
      (effects (font (size 1.27 1.27)) (justify left bottom) hide)
    )
    (pin "1")
    (pin "2")
    (instances
      (project "data-center-rdimm-ddr4-tester"
        (path ""
          (reference "C60") (unit 1)
        )
      )
    )
  )

  (symbol (lib_id "antmicropower:GND") (at 52.07 71.12 0) (mirror y) (unit 1)
    (in_bom yes) (on_board yes) (dnp no) (fields_autoplaced)
    (property "Reference" "#PWR0181" (at 52.07 77.47 0)
      (effects (font (size 1.27 1.27)) hide)
    )
    (property "Value" "GND" (at 52.07 76.2 0)
      (effects (font (size 1.27 1.27)))
    )
    (property "Footprint" "" (at 52.07 71.12 0)
      (effects (font (size 1.27 1.27)) hide)
    )
    (property "Datasheet" "" (at 52.07 71.12 0)
      (effects (font (size 1.27 1.27)) hide)
    )
    (property "Author" "Antmicro" (at 43.18 78.74 0)
      (effects (font (size 1.27 1.27) (thickness 0.15)) (justify left bottom) hide)
    )
    (property "License" "Apache-2.0" (at 43.18 81.28 0)
      (effects (font (size 1.27 1.27) (thickness 0.15)) (justify left bottom) hide)
    )
    (pin "1")
    (instances
      (project "data-center-rdimm-ddr4-tester"
        (path ""
          (reference "#PWR0181") (unit 1)
        )
      )
    )
  )

  (symbol (lib_id "antmicroCapacitorsmisc:C_100n_0201") (at 59.055 66.04 270) (unit 1)
    (in_bom yes) (on_board yes) (dnp no)
    (property "Reference" "C61" (at 59.055 66.675 90)
      (effects (font (size 1.524 1.524)) (justify left))
    )
    (property "Value" "C_100n_0201" (at 48.895 86.36 0)
      (effects (font (size 1.27 1.27) (thickness 0.15)) (justify left bottom) hide)
    )
    (property "Footprint" "antmicro-footprints:C_0201" (at 46.355 86.36 0)
      (effects (font (size 1.27 1.27) (thickness 0.15)) (justify left bottom) hide)
    )
    (property "Datasheet" " " (at 43.815 86.36 0)
      (effects (font (size 1.27 1.27) (thickness 0.15)) (justify left bottom) hide)
    )
    (property "Manufacturer" "Yaego" (at 38.735 86.36 0)
      (effects (font (size 1.27 1.27) (thickness 0.15)) (justify left bottom) hide)
    )
    (property "MPN" "CC0201KRX6S5BB104" (at 41.275 86.36 0)
      (effects (font (size 1.27 1.27) (thickness 0.15)) (justify left bottom) hide)
    )
    (property "Val" "100n" (at 59.055 70.485 90)
      (effects (font (size 1.27 1.27) (thickness 0.15)) (justify left))
    )
    (property "License" "Apache-2.0" (at 36.195 86.36 0)
      (effects (font (size 1.27 1.27) (thickness 0.15)) (justify left bottom) hide)
    )
    (property "Author" "Antmicro" (at 33.655 86.36 0)
      (effects (font (size 1.27 1.27) (thickness 0.15)) (justify left bottom) hide)
    )
    (property "Voltage" "" (at 31.115 86.36 0)
      (effects (font (size 1.27 1.27)) (justify left bottom) hide)
    )
    (property "Dielectric" "" (at 28.575 86.36 0)
      (effects (font (size 1.27 1.27)) (justify left bottom) hide)
    )
    (pin "1")
    (pin "2")
    (instances
      (project "data-center-rdimm-ddr4-tester"
        (path ""
          (reference "C61") (unit 1)
        )
      )
    )
  )

  (symbol (lib_id "antmicropower:GND") (at 59.055 71.12 0) (mirror y) (unit 1)
    (in_bom yes) (on_board yes) (dnp no) (fields_autoplaced)
    (property "Reference" "#PWR0182" (at 59.055 77.47 0)
      (effects (font (size 1.27 1.27)) hide)
    )
    (property "Value" "GND" (at 59.055 76.2 0)
      (effects (font (size 1.27 1.27)))
    )
    (property "Footprint" "" (at 59.055 71.12 0)
      (effects (font (size 1.27 1.27)) hide)
    )
    (property "Datasheet" "" (at 59.055 71.12 0)
      (effects (font (size 1.27 1.27)) hide)
    )
    (property "Author" "Antmicro" (at 50.165 78.74 0)
      (effects (font (size 1.27 1.27) (thickness 0.15)) (justify left bottom) hide)
    )
    (property "License" "Apache-2.0" (at 50.165 81.28 0)
      (effects (font (size 1.27 1.27) (thickness 0.15)) (justify left bottom) hide)
    )
    (pin "1")
    (instances
      (project "data-center-rdimm-ddr4-tester"
        (path ""
          (reference "#PWR0182") (unit 1)
        )
      )
    )
  )

  (symbol (lib_id "antmicroCapacitorsmisc:C_100n_0201") (at 107.95 104.775 270) (unit 1)
    (in_bom yes) (on_board yes) (dnp no)
    (property "Reference" "C56" (at 107.95 105.41 90)
      (effects (font (size 1.524 1.524)) (justify left))
    )
    (property "Value" "C_100n_0201" (at 97.79 125.095 0)
      (effects (font (size 1.27 1.27) (thickness 0.15)) (justify left bottom) hide)
    )
    (property "Footprint" "antmicro-footprints:C_0201" (at 95.25 125.095 0)
      (effects (font (size 1.27 1.27) (thickness 0.15)) (justify left bottom) hide)
    )
    (property "Datasheet" " " (at 92.71 125.095 0)
      (effects (font (size 1.27 1.27) (thickness 0.15)) (justify left bottom) hide)
    )
    (property "Manufacturer" "Yaego" (at 87.63 125.095 0)
      (effects (font (size 1.27 1.27) (thickness 0.15)) (justify left bottom) hide)
    )
    (property "MPN" "CC0201KRX6S5BB104" (at 90.17 125.095 0)
      (effects (font (size 1.27 1.27) (thickness 0.15)) (justify left bottom) hide)
    )
    (property "Val" "100n" (at 107.95 109.22 90)
      (effects (font (size 1.27 1.27) (thickness 0.15)) (justify left))
    )
    (property "License" "Apache-2.0" (at 85.09 125.095 0)
      (effects (font (size 1.27 1.27) (thickness 0.15)) (justify left bottom) hide)
    )
    (property "Author" "Antmicro" (at 82.55 125.095 0)
      (effects (font (size 1.27 1.27) (thickness 0.15)) (justify left bottom) hide)
    )
    (property "Voltage" "" (at 80.01 125.095 0)
      (effects (font (size 1.27 1.27)) (justify left bottom) hide)
    )
    (property "Dielectric" "" (at 77.47 125.095 0)
      (effects (font (size 1.27 1.27)) (justify left bottom) hide)
    )
    (pin "1")
    (pin "2")
    (instances
      (project "data-center-rdimm-ddr4-tester"
        (path ""
          (reference "C56") (unit 1)
        )
      )
    )
  )

  (symbol (lib_id "antmicropower:GND") (at 107.95 109.855 0) (mirror y) (unit 1)
    (in_bom yes) (on_board yes) (dnp no) (fields_autoplaced)
    (property "Reference" "#PWR0193" (at 107.95 116.205 0)
      (effects (font (size 1.27 1.27)) hide)
    )
    (property "Value" "GND" (at 107.95 114.3 0)
      (effects (font (size 1.27 1.27)))
    )
    (property "Footprint" "" (at 107.95 109.855 0)
      (effects (font (size 1.27 1.27)) hide)
    )
    (property "Datasheet" "" (at 107.95 109.855 0)
      (effects (font (size 1.27 1.27)) hide)
    )
    (property "Author" "Antmicro" (at 99.06 117.475 0)
      (effects (font (size 1.27 1.27) (thickness 0.15)) (justify left bottom) hide)
    )
    (property "License" "Apache-2.0" (at 99.06 120.015 0)
      (effects (font (size 1.27 1.27) (thickness 0.15)) (justify left bottom) hide)
    )
    (pin "1")
    (instances
      (project "data-center-rdimm-ddr4-tester"
        (path ""
          (reference "#PWR0193") (unit 1)
        )
      )
    )
  )

  (symbol (lib_id "antmicropower:GND") (at 102.87 206.375 0) (unit 1)
    (in_bom yes) (on_board yes) (dnp no) (fields_autoplaced)
    (property "Reference" "#PWR0253" (at 102.87 212.725 0)
      (effects (font (size 1.27 1.27)) hide)
    )
    (property "Value" "GND" (at 102.87 211.455 0)
      (effects (font (size 1.27 1.27)))
    )
    (property "Footprint" "" (at 102.87 206.375 0)
      (effects (font (size 1.27 1.27)) hide)
    )
    (property "Datasheet" "" (at 102.87 206.375 0)
      (effects (font (size 1.27 1.27)) hide)
    )
    (property "Author" "Antmicro" (at 111.76 213.995 0)
      (effects (font (size 1.27 1.27) (thickness 0.15)) (justify left bottom) hide)
    )
    (property "License" "Apache-2.0" (at 111.76 216.535 0)
      (effects (font (size 1.27 1.27) (thickness 0.15)) (justify left bottom) hide)
    )
    (pin "1")
    (instances
      (project "data-center-rdimm-ddr4-tester"
        (path ""
          (reference "#PWR0253") (unit 1)
        )
      )
    )
  )

  (symbol (lib_id "antmicropower:GND") (at 109.22 206.375 0) (unit 1)
    (in_bom yes) (on_board yes) (dnp no) (fields_autoplaced)
    (property "Reference" "#PWR0254" (at 109.22 212.725 0)
      (effects (font (size 1.27 1.27)) hide)
    )
    (property "Value" "GND" (at 109.22 211.455 0)
      (effects (font (size 1.27 1.27)))
    )
    (property "Footprint" "" (at 109.22 206.375 0)
      (effects (font (size 1.27 1.27)) hide)
    )
    (property "Datasheet" "" (at 109.22 206.375 0)
      (effects (font (size 1.27 1.27)) hide)
    )
    (property "Author" "Antmicro" (at 118.11 213.995 0)
      (effects (font (size 1.27 1.27) (thickness 0.15)) (justify left bottom) hide)
    )
    (property "License" "Apache-2.0" (at 118.11 216.535 0)
      (effects (font (size 1.27 1.27) (thickness 0.15)) (justify left bottom) hide)
    )
    (pin "1")
    (instances
      (project "data-center-rdimm-ddr4-tester"
        (path ""
          (reference "#PWR0254") (unit 1)
        )
      )
    )
  )

  (symbol (lib_id "antmicroCapacitorsmisc:C_100n_0201") (at 66.04 66.04 270) (unit 1)
    (in_bom yes) (on_board yes) (dnp no)
    (property "Reference" "C62" (at 66.04 66.675 90)
      (effects (font (size 1.524 1.524)) (justify left))
    )
    (property "Value" "C_100n_0201" (at 55.88 86.36 0)
      (effects (font (size 1.27 1.27) (thickness 0.15)) (justify left bottom) hide)
    )
    (property "Footprint" "antmicro-footprints:C_0201" (at 53.34 86.36 0)
      (effects (font (size 1.27 1.27) (thickness 0.15)) (justify left bottom) hide)
    )
    (property "Datasheet" " " (at 50.8 86.36 0)
      (effects (font (size 1.27 1.27) (thickness 0.15)) (justify left bottom) hide)
    )
    (property "Manufacturer" "Yaego" (at 45.72 86.36 0)
      (effects (font (size 1.27 1.27) (thickness 0.15)) (justify left bottom) hide)
    )
    (property "MPN" "CC0201KRX6S5BB104" (at 48.26 86.36 0)
      (effects (font (size 1.27 1.27) (thickness 0.15)) (justify left bottom) hide)
    )
    (property "Val" "100n" (at 66.04 70.485 90)
      (effects (font (size 1.27 1.27) (thickness 0.15)) (justify left))
    )
    (property "License" "Apache-2.0" (at 43.18 86.36 0)
      (effects (font (size 1.27 1.27) (thickness 0.15)) (justify left bottom) hide)
    )
    (property "Author" "Antmicro" (at 40.64 86.36 0)
      (effects (font (size 1.27 1.27) (thickness 0.15)) (justify left bottom) hide)
    )
    (property "Voltage" "" (at 38.1 86.36 0)
      (effects (font (size 1.27 1.27)) (justify left bottom) hide)
    )
    (property "Dielectric" "" (at 35.56 86.36 0)
      (effects (font (size 1.27 1.27)) (justify left bottom) hide)
    )
    (pin "1")
    (pin "2")
    (instances
      (project "data-center-rdimm-ddr4-tester"
        (path ""
          (reference "C62") (unit 1)
        )
      )
    )
  )

  (symbol (lib_id "antmicropower:GND") (at 66.04 71.12 0) (mirror y) (unit 1)
    (in_bom yes) (on_board yes) (dnp no) (fields_autoplaced)
    (property "Reference" "#PWR0194" (at 66.04 77.47 0)
      (effects (font (size 1.27 1.27)) hide)
    )
    (property "Value" "GND" (at 66.04 76.2 0)
      (effects (font (size 1.27 1.27)))
    )
    (property "Footprint" "" (at 66.04 71.12 0)
      (effects (font (size 1.27 1.27)) hide)
    )
    (property "Datasheet" "" (at 66.04 71.12 0)
      (effects (font (size 1.27 1.27)) hide)
    )
    (property "Author" "Antmicro" (at 57.15 78.74 0)
      (effects (font (size 1.27 1.27) (thickness 0.15)) (justify left bottom) hide)
    )
    (property "License" "Apache-2.0" (at 57.15 81.28 0)
      (effects (font (size 1.27 1.27) (thickness 0.15)) (justify left bottom) hide)
    )
    (pin "1")
    (instances
      (project "data-center-rdimm-ddr4-tester"
        (path ""
          (reference "#PWR0194") (unit 1)
        )
      )
    )
  )

  (symbol (lib_id "antmicroCapacitorsmisc:C_100n_0201") (at 73.025 66.04 270) (unit 1)
    (in_bom yes) (on_board yes) (dnp no)
    (property "Reference" "C63" (at 73.025 66.675 90)
      (effects (font (size 1.524 1.524)) (justify left))
    )
    (property "Value" "C_100n_0201" (at 62.865 86.36 0)
      (effects (font (size 1.27 1.27) (thickness 0.15)) (justify left bottom) hide)
    )
    (property "Footprint" "antmicro-footprints:C_0201" (at 60.325 86.36 0)
      (effects (font (size 1.27 1.27) (thickness 0.15)) (justify left bottom) hide)
    )
    (property "Datasheet" " " (at 57.785 86.36 0)
      (effects (font (size 1.27 1.27) (thickness 0.15)) (justify left bottom) hide)
    )
    (property "Manufacturer" "Yaego" (at 52.705 86.36 0)
      (effects (font (size 1.27 1.27) (thickness 0.15)) (justify left bottom) hide)
    )
    (property "MPN" "CC0201KRX6S5BB104" (at 55.245 86.36 0)
      (effects (font (size 1.27 1.27) (thickness 0.15)) (justify left bottom) hide)
    )
    (property "Val" "100n" (at 73.025 70.485 90)
      (effects (font (size 1.27 1.27) (thickness 0.15)) (justify left))
    )
    (property "License" "Apache-2.0" (at 50.165 86.36 0)
      (effects (font (size 1.27 1.27) (thickness 0.15)) (justify left bottom) hide)
    )
    (property "Author" "Antmicro" (at 47.625 86.36 0)
      (effects (font (size 1.27 1.27) (thickness 0.15)) (justify left bottom) hide)
    )
    (property "Voltage" "" (at 45.085 86.36 0)
      (effects (font (size 1.27 1.27)) (justify left bottom) hide)
    )
    (property "Dielectric" "" (at 42.545 86.36 0)
      (effects (font (size 1.27 1.27)) (justify left bottom) hide)
    )
    (pin "1")
    (pin "2")
    (instances
      (project "data-center-rdimm-ddr4-tester"
        (path ""
          (reference "C63") (unit 1)
        )
      )
    )
  )

  (symbol (lib_id "antmicropower:GND") (at 73.025 71.12 0) (mirror y) (unit 1)
    (in_bom yes) (on_board yes) (dnp no) (fields_autoplaced)
    (property "Reference" "#PWR0195" (at 73.025 77.47 0)
      (effects (font (size 1.27 1.27)) hide)
    )
    (property "Value" "GND" (at 73.025 76.2 0)
      (effects (font (size 1.27 1.27)))
    )
    (property "Footprint" "" (at 73.025 71.12 0)
      (effects (font (size 1.27 1.27)) hide)
    )
    (property "Datasheet" "" (at 73.025 71.12 0)
      (effects (font (size 1.27 1.27)) hide)
    )
    (property "Author" "Antmicro" (at 64.135 78.74 0)
      (effects (font (size 1.27 1.27) (thickness 0.15)) (justify left bottom) hide)
    )
    (property "License" "Apache-2.0" (at 64.135 81.28 0)
      (effects (font (size 1.27 1.27) (thickness 0.15)) (justify left bottom) hide)
    )
    (pin "1")
    (instances
      (project "data-center-rdimm-ddr4-tester"
        (path ""
          (reference "#PWR0195") (unit 1)
        )
      )
    )
  )

  (symbol (lib_id "antmicroCapacitorsmisc:C_100n_0201") (at 80.01 66.04 270) (unit 1)
    (in_bom yes) (on_board yes) (dnp no)
    (property "Reference" "C64" (at 80.01 66.675 90)
      (effects (font (size 1.524 1.524)) (justify left))
    )
    (property "Value" "C_100n_0201" (at 69.85 86.36 0)
      (effects (font (size 1.27 1.27) (thickness 0.15)) (justify left bottom) hide)
    )
    (property "Footprint" "antmicro-footprints:C_0201" (at 67.31 86.36 0)
      (effects (font (size 1.27 1.27) (thickness 0.15)) (justify left bottom) hide)
    )
    (property "Datasheet" " " (at 64.77 86.36 0)
      (effects (font (size 1.27 1.27) (thickness 0.15)) (justify left bottom) hide)
    )
    (property "Manufacturer" "Yaego" (at 59.69 86.36 0)
      (effects (font (size 1.27 1.27) (thickness 0.15)) (justify left bottom) hide)
    )
    (property "MPN" "CC0201KRX6S5BB104" (at 62.23 86.36 0)
      (effects (font (size 1.27 1.27) (thickness 0.15)) (justify left bottom) hide)
    )
    (property "Val" "100n" (at 80.01 70.485 90)
      (effects (font (size 1.27 1.27) (thickness 0.15)) (justify left))
    )
    (property "License" "Apache-2.0" (at 57.15 86.36 0)
      (effects (font (size 1.27 1.27) (thickness 0.15)) (justify left bottom) hide)
    )
    (property "Author" "Antmicro" (at 54.61 86.36 0)
      (effects (font (size 1.27 1.27) (thickness 0.15)) (justify left bottom) hide)
    )
    (property "Voltage" "" (at 52.07 86.36 0)
      (effects (font (size 1.27 1.27)) (justify left bottom) hide)
    )
    (property "Dielectric" "" (at 49.53 86.36 0)
      (effects (font (size 1.27 1.27)) (justify left bottom) hide)
    )
    (pin "1")
    (pin "2")
    (instances
      (project "data-center-rdimm-ddr4-tester"
        (path ""
          (reference "C64") (unit 1)
        )
      )
    )
  )

  (symbol (lib_id "antmicropower:GND") (at 80.01 71.12 0) (mirror y) (unit 1)
    (in_bom yes) (on_board yes) (dnp no) (fields_autoplaced)
    (property "Reference" "#PWR0196" (at 80.01 77.47 0)
      (effects (font (size 1.27 1.27)) hide)
    )
    (property "Value" "GND" (at 80.01 76.2 0)
      (effects (font (size 1.27 1.27)))
    )
    (property "Footprint" "" (at 80.01 71.12 0)
      (effects (font (size 1.27 1.27)) hide)
    )
    (property "Datasheet" "" (at 80.01 71.12 0)
      (effects (font (size 1.27 1.27)) hide)
    )
    (property "Author" "Antmicro" (at 71.12 78.74 0)
      (effects (font (size 1.27 1.27) (thickness 0.15)) (justify left bottom) hide)
    )
    (property "License" "Apache-2.0" (at 71.12 81.28 0)
      (effects (font (size 1.27 1.27) (thickness 0.15)) (justify left bottom) hide)
    )
    (pin "1")
    (instances
      (project "data-center-rdimm-ddr4-tester"
        (path ""
          (reference "#PWR0196") (unit 1)
        )
      )
    )
  )

  (symbol (lib_id "antmicroCapacitorsmisc:C_100n_0201") (at 86.995 66.04 270) (unit 1)
    (in_bom yes) (on_board yes) (dnp no)
    (property "Reference" "C65" (at 86.995 66.675 90)
      (effects (font (size 1.524 1.524)) (justify left))
    )
    (property "Value" "C_100n_0201" (at 76.835 86.36 0)
      (effects (font (size 1.27 1.27) (thickness 0.15)) (justify left bottom) hide)
    )
    (property "Footprint" "antmicro-footprints:C_0201" (at 74.295 86.36 0)
      (effects (font (size 1.27 1.27) (thickness 0.15)) (justify left bottom) hide)
    )
    (property "Datasheet" " " (at 71.755 86.36 0)
      (effects (font (size 1.27 1.27) (thickness 0.15)) (justify left bottom) hide)
    )
    (property "Manufacturer" "Yaego" (at 66.675 86.36 0)
      (effects (font (size 1.27 1.27) (thickness 0.15)) (justify left bottom) hide)
    )
    (property "MPN" "CC0201KRX6S5BB104" (at 69.215 86.36 0)
      (effects (font (size 1.27 1.27) (thickness 0.15)) (justify left bottom) hide)
    )
    (property "Val" "100n" (at 86.995 70.485 90)
      (effects (font (size 1.27 1.27) (thickness 0.15)) (justify left))
    )
    (property "License" "Apache-2.0" (at 64.135 86.36 0)
      (effects (font (size 1.27 1.27) (thickness 0.15)) (justify left bottom) hide)
    )
    (property "Author" "Antmicro" (at 61.595 86.36 0)
      (effects (font (size 1.27 1.27) (thickness 0.15)) (justify left bottom) hide)
    )
    (property "Voltage" "" (at 59.055 86.36 0)
      (effects (font (size 1.27 1.27)) (justify left bottom) hide)
    )
    (property "Dielectric" "" (at 56.515 86.36 0)
      (effects (font (size 1.27 1.27)) (justify left bottom) hide)
    )
    (pin "1")
    (pin "2")
    (instances
      (project "data-center-rdimm-ddr4-tester"
        (path ""
          (reference "C65") (unit 1)
        )
      )
    )
  )

  (symbol (lib_id "antmicropower:GND") (at 86.995 71.12 0) (mirror y) (unit 1)
    (in_bom yes) (on_board yes) (dnp no) (fields_autoplaced)
    (property "Reference" "#PWR0197" (at 86.995 77.47 0)
      (effects (font (size 1.27 1.27)) hide)
    )
    (property "Value" "GND" (at 86.995 76.2 0)
      (effects (font (size 1.27 1.27)))
    )
    (property "Footprint" "" (at 86.995 71.12 0)
      (effects (font (size 1.27 1.27)) hide)
    )
    (property "Datasheet" "" (at 86.995 71.12 0)
      (effects (font (size 1.27 1.27)) hide)
    )
    (property "Author" "Antmicro" (at 78.105 78.74 0)
      (effects (font (size 1.27 1.27) (thickness 0.15)) (justify left bottom) hide)
    )
    (property "License" "Apache-2.0" (at 78.105 81.28 0)
      (effects (font (size 1.27 1.27) (thickness 0.15)) (justify left bottom) hide)
    )
    (pin "1")
    (instances
      (project "data-center-rdimm-ddr4-tester"
        (path ""
          (reference "#PWR0197") (unit 1)
        )
      )
    )
  )

  (symbol (lib_id "antmicroCapacitorsmisc:C_100n_0201") (at 93.98 66.04 270) (unit 1)
    (in_bom yes) (on_board yes) (dnp no)
    (property "Reference" "C66" (at 93.98 66.675 90)
      (effects (font (size 1.524 1.524)) (justify left))
    )
    (property "Value" "C_100n_0201" (at 83.82 86.36 0)
      (effects (font (size 1.27 1.27) (thickness 0.15)) (justify left bottom) hide)
    )
    (property "Footprint" "antmicro-footprints:C_0201" (at 81.28 86.36 0)
      (effects (font (size 1.27 1.27) (thickness 0.15)) (justify left bottom) hide)
    )
    (property "Datasheet" " " (at 78.74 86.36 0)
      (effects (font (size 1.27 1.27) (thickness 0.15)) (justify left bottom) hide)
    )
    (property "Manufacturer" "Yaego" (at 73.66 86.36 0)
      (effects (font (size 1.27 1.27) (thickness 0.15)) (justify left bottom) hide)
    )
    (property "MPN" "CC0201KRX6S5BB104" (at 76.2 86.36 0)
      (effects (font (size 1.27 1.27) (thickness 0.15)) (justify left bottom) hide)
    )
    (property "Val" "100n" (at 93.98 70.485 90)
      (effects (font (size 1.27 1.27) (thickness 0.15)) (justify left))
    )
    (property "License" "Apache-2.0" (at 71.12 86.36 0)
      (effects (font (size 1.27 1.27) (thickness 0.15)) (justify left bottom) hide)
    )
    (property "Author" "Antmicro" (at 68.58 86.36 0)
      (effects (font (size 1.27 1.27) (thickness 0.15)) (justify left bottom) hide)
    )
    (property "Voltage" "" (at 66.04 86.36 0)
      (effects (font (size 1.27 1.27)) (justify left bottom) hide)
    )
    (property "Dielectric" "" (at 63.5 86.36 0)
      (effects (font (size 1.27 1.27)) (justify left bottom) hide)
    )
    (pin "1")
    (pin "2")
    (instances
      (project "data-center-rdimm-ddr4-tester"
        (path ""
          (reference "C66") (unit 1)
        )
      )
    )
  )

  (symbol (lib_id "antmicropower:GND") (at 93.98 71.12 0) (mirror y) (unit 1)
    (in_bom yes) (on_board yes) (dnp no) (fields_autoplaced)
    (property "Reference" "#PWR0198" (at 93.98 77.47 0)
      (effects (font (size 1.27 1.27)) hide)
    )
    (property "Value" "GND" (at 93.98 76.2 0)
      (effects (font (size 1.27 1.27)))
    )
    (property "Footprint" "" (at 93.98 71.12 0)
      (effects (font (size 1.27 1.27)) hide)
    )
    (property "Datasheet" "" (at 93.98 71.12 0)
      (effects (font (size 1.27 1.27)) hide)
    )
    (property "Author" "Antmicro" (at 85.09 78.74 0)
      (effects (font (size 1.27 1.27) (thickness 0.15)) (justify left bottom) hide)
    )
    (property "License" "Apache-2.0" (at 85.09 81.28 0)
      (effects (font (size 1.27 1.27) (thickness 0.15)) (justify left bottom) hide)
    )
    (pin "1")
    (instances
      (project "data-center-rdimm-ddr4-tester"
        (path ""
          (reference "#PWR0198") (unit 1)
        )
      )
    )
  )

  (symbol (lib_id "antmicropower:GND") (at 116.205 206.375 0) (unit 1)
    (in_bom yes) (on_board yes) (dnp no) (fields_autoplaced)
    (property "Reference" "#PWR0255" (at 116.205 212.725 0)
      (effects (font (size 1.27 1.27)) hide)
    )
    (property "Value" "GND" (at 116.205 211.455 0)
      (effects (font (size 1.27 1.27)))
    )
    (property "Footprint" "" (at 116.205 206.375 0)
      (effects (font (size 1.27 1.27)) hide)
    )
    (property "Datasheet" "" (at 116.205 206.375 0)
      (effects (font (size 1.27 1.27)) hide)
    )
    (property "Author" "Antmicro" (at 125.095 213.995 0)
      (effects (font (size 1.27 1.27) (thickness 0.15)) (justify left bottom) hide)
    )
    (property "License" "Apache-2.0" (at 125.095 216.535 0)
      (effects (font (size 1.27 1.27) (thickness 0.15)) (justify left bottom) hide)
    )
    (pin "1")
    (instances
      (project "data-center-rdimm-ddr4-tester"
        (path ""
          (reference "#PWR0255") (unit 1)
        )
      )
    )
  )

  (symbol (lib_id "antmicroCapacitorsmisc:C_100n_0201") (at 100.965 66.04 270) (unit 1)
    (in_bom yes) (on_board yes) (dnp no)
    (property "Reference" "C67" (at 100.965 66.675 90)
      (effects (font (size 1.524 1.524)) (justify left))
    )
    (property "Value" "C_100n_0201" (at 90.805 86.36 0)
      (effects (font (size 1.27 1.27) (thickness 0.15)) (justify left bottom) hide)
    )
    (property "Footprint" "antmicro-footprints:C_0201" (at 88.265 86.36 0)
      (effects (font (size 1.27 1.27) (thickness 0.15)) (justify left bottom) hide)
    )
    (property "Datasheet" " " (at 85.725 86.36 0)
      (effects (font (size 1.27 1.27) (thickness 0.15)) (justify left bottom) hide)
    )
    (property "Manufacturer" "Yaego" (at 80.645 86.36 0)
      (effects (font (size 1.27 1.27) (thickness 0.15)) (justify left bottom) hide)
    )
    (property "MPN" "CC0201KRX6S5BB104" (at 83.185 86.36 0)
      (effects (font (size 1.27 1.27) (thickness 0.15)) (justify left bottom) hide)
    )
    (property "Val" "100n" (at 100.965 70.485 90)
      (effects (font (size 1.27 1.27) (thickness 0.15)) (justify left))
    )
    (property "License" "Apache-2.0" (at 78.105 86.36 0)
      (effects (font (size 1.27 1.27) (thickness 0.15)) (justify left bottom) hide)
    )
    (property "Author" "Antmicro" (at 75.565 86.36 0)
      (effects (font (size 1.27 1.27) (thickness 0.15)) (justify left bottom) hide)
    )
    (property "Voltage" "" (at 73.025 86.36 0)
      (effects (font (size 1.27 1.27)) (justify left bottom) hide)
    )
    (property "Dielectric" "" (at 70.485 86.36 0)
      (effects (font (size 1.27 1.27)) (justify left bottom) hide)
    )
    (pin "1")
    (pin "2")
    (instances
      (project "data-center-rdimm-ddr4-tester"
        (path ""
          (reference "C67") (unit 1)
        )
      )
    )
  )

  (symbol (lib_id "antmicropower:GND") (at 100.965 71.12 0) (mirror y) (unit 1)
    (in_bom yes) (on_board yes) (dnp no) (fields_autoplaced)
    (property "Reference" "#PWR0199" (at 100.965 77.47 0)
      (effects (font (size 1.27 1.27)) hide)
    )
    (property "Value" "GND" (at 100.965 76.2 0)
      (effects (font (size 1.27 1.27)))
    )
    (property "Footprint" "" (at 100.965 71.12 0)
      (effects (font (size 1.27 1.27)) hide)
    )
    (property "Datasheet" "" (at 100.965 71.12 0)
      (effects (font (size 1.27 1.27)) hide)
    )
    (property "Author" "Antmicro" (at 92.075 78.74 0)
      (effects (font (size 1.27 1.27) (thickness 0.15)) (justify left bottom) hide)
    )
    (property "License" "Apache-2.0" (at 92.075 81.28 0)
      (effects (font (size 1.27 1.27) (thickness 0.15)) (justify left bottom) hide)
    )
    (pin "1")
    (instances
      (project "data-center-rdimm-ddr4-tester"
        (path ""
          (reference "#PWR0199") (unit 1)
        )
      )
    )
  )

  (symbol (lib_id "antmicroCapacitorsmisc:C_100n_0201") (at 107.95 66.04 270) (unit 1)
    (in_bom yes) (on_board yes) (dnp no)
    (property "Reference" "C68" (at 107.95 66.675 90)
      (effects (font (size 1.524 1.524)) (justify left))
    )
    (property "Value" "C_100n_0201" (at 97.79 86.36 0)
      (effects (font (size 1.27 1.27) (thickness 0.15)) (justify left bottom) hide)
    )
    (property "Footprint" "antmicro-footprints:C_0201" (at 95.25 86.36 0)
      (effects (font (size 1.27 1.27) (thickness 0.15)) (justify left bottom) hide)
    )
    (property "Datasheet" " " (at 92.71 86.36 0)
      (effects (font (size 1.27 1.27) (thickness 0.15)) (justify left bottom) hide)
    )
    (property "Manufacturer" "Yaego" (at 87.63 86.36 0)
      (effects (font (size 1.27 1.27) (thickness 0.15)) (justify left bottom) hide)
    )
    (property "MPN" "CC0201KRX6S5BB104" (at 90.17 86.36 0)
      (effects (font (size 1.27 1.27) (thickness 0.15)) (justify left bottom) hide)
    )
    (property "Val" "100n" (at 107.95 70.485 90)
      (effects (font (size 1.27 1.27) (thickness 0.15)) (justify left))
    )
    (property "License" "Apache-2.0" (at 85.09 86.36 0)
      (effects (font (size 1.27 1.27) (thickness 0.15)) (justify left bottom) hide)
    )
    (property "Author" "Antmicro" (at 82.55 86.36 0)
      (effects (font (size 1.27 1.27) (thickness 0.15)) (justify left bottom) hide)
    )
    (property "Voltage" "" (at 80.01 86.36 0)
      (effects (font (size 1.27 1.27)) (justify left bottom) hide)
    )
    (property "Dielectric" "" (at 77.47 86.36 0)
      (effects (font (size 1.27 1.27)) (justify left bottom) hide)
    )
    (pin "1")
    (pin "2")
    (instances
      (project "data-center-rdimm-ddr4-tester"
        (path ""
          (reference "C68") (unit 1)
        )
      )
    )
  )

  (symbol (lib_id "antmicropower:GND") (at 107.95 71.12 0) (mirror y) (unit 1)
    (in_bom yes) (on_board yes) (dnp no) (fields_autoplaced)
    (property "Reference" "#PWR0200" (at 107.95 77.47 0)
      (effects (font (size 1.27 1.27)) hide)
    )
    (property "Value" "GND" (at 107.95 76.2 0)
      (effects (font (size 1.27 1.27)))
    )
    (property "Footprint" "" (at 107.95 71.12 0)
      (effects (font (size 1.27 1.27)) hide)
    )
    (property "Datasheet" "" (at 107.95 71.12 0)
      (effects (font (size 1.27 1.27)) hide)
    )
    (property "Author" "Antmicro" (at 99.06 78.74 0)
      (effects (font (size 1.27 1.27) (thickness 0.15)) (justify left bottom) hide)
    )
    (property "License" "Apache-2.0" (at 99.06 81.28 0)
      (effects (font (size 1.27 1.27) (thickness 0.15)) (justify left bottom) hide)
    )
    (pin "1")
    (instances
      (project "data-center-rdimm-ddr4-tester"
        (path ""
          (reference "#PWR0200") (unit 1)
        )
      )
    )
  )

  (symbol (lib_id "antmicroCapacitorsmisc:C_100n_0201") (at 114.3 66.04 270) (unit 1)
    (in_bom yes) (on_board yes) (dnp no)
    (property "Reference" "C69" (at 114.3 66.675 90)
      (effects (font (size 1.524 1.524)) (justify left))
    )
    (property "Value" "C_100n_0201" (at 104.14 86.36 0)
      (effects (font (size 1.27 1.27) (thickness 0.15)) (justify left bottom) hide)
    )
    (property "Footprint" "antmicro-footprints:C_0201" (at 101.6 86.36 0)
      (effects (font (size 1.27 1.27) (thickness 0.15)) (justify left bottom) hide)
    )
    (property "Datasheet" " " (at 99.06 86.36 0)
      (effects (font (size 1.27 1.27) (thickness 0.15)) (justify left bottom) hide)
    )
    (property "Manufacturer" "Yaego" (at 93.98 86.36 0)
      (effects (font (size 1.27 1.27) (thickness 0.15)) (justify left bottom) hide)
    )
    (property "MPN" "CC0201KRX6S5BB104" (at 96.52 86.36 0)
      (effects (font (size 1.27 1.27) (thickness 0.15)) (justify left bottom) hide)
    )
    (property "Val" "100n" (at 114.3 70.485 90)
      (effects (font (size 1.27 1.27) (thickness 0.15)) (justify left))
    )
    (property "License" "Apache-2.0" (at 91.44 86.36 0)
      (effects (font (size 1.27 1.27) (thickness 0.15)) (justify left bottom) hide)
    )
    (property "Author" "Antmicro" (at 88.9 86.36 0)
      (effects (font (size 1.27 1.27) (thickness 0.15)) (justify left bottom) hide)
    )
    (property "Voltage" "" (at 86.36 86.36 0)
      (effects (font (size 1.27 1.27)) (justify left bottom) hide)
    )
    (property "Dielectric" "" (at 83.82 86.36 0)
      (effects (font (size 1.27 1.27)) (justify left bottom) hide)
    )
    (pin "1")
    (pin "2")
    (instances
      (project "data-center-rdimm-ddr4-tester"
        (path ""
          (reference "C69") (unit 1)
        )
      )
    )
  )

  (symbol (lib_id "antmicropower:GND") (at 114.3 71.12 0) (mirror y) (unit 1)
    (in_bom yes) (on_board yes) (dnp no) (fields_autoplaced)
    (property "Reference" "#PWR0201" (at 114.3 77.47 0)
      (effects (font (size 1.27 1.27)) hide)
    )
    (property "Value" "GND" (at 114.3 76.2 0)
      (effects (font (size 1.27 1.27)))
    )
    (property "Footprint" "" (at 114.3 71.12 0)
      (effects (font (size 1.27 1.27)) hide)
    )
    (property "Datasheet" "" (at 114.3 71.12 0)
      (effects (font (size 1.27 1.27)) hide)
    )
    (property "Author" "Antmicro" (at 105.41 78.74 0)
      (effects (font (size 1.27 1.27) (thickness 0.15)) (justify left bottom) hide)
    )
    (property "License" "Apache-2.0" (at 105.41 81.28 0)
      (effects (font (size 1.27 1.27) (thickness 0.15)) (justify left bottom) hide)
    )
    (pin "1")
    (instances
      (project "data-center-rdimm-ddr4-tester"
        (path ""
          (reference "#PWR0201") (unit 1)
        )
      )
    )
  )

  (symbol (lib_id "antmicroCapacitorsmisc:C_100n_0201") (at 121.285 66.04 270) (unit 1)
    (in_bom yes) (on_board yes) (dnp no)
    (property "Reference" "C70" (at 121.285 66.675 90)
      (effects (font (size 1.524 1.524)) (justify left))
    )
    (property "Value" "C_100n_0201" (at 111.125 86.36 0)
      (effects (font (size 1.27 1.27) (thickness 0.15)) (justify left bottom) hide)
    )
    (property "Footprint" "antmicro-footprints:C_0201" (at 108.585 86.36 0)
      (effects (font (size 1.27 1.27) (thickness 0.15)) (justify left bottom) hide)
    )
    (property "Datasheet" " " (at 106.045 86.36 0)
      (effects (font (size 1.27 1.27) (thickness 0.15)) (justify left bottom) hide)
    )
    (property "Manufacturer" "Yaego" (at 100.965 86.36 0)
      (effects (font (size 1.27 1.27) (thickness 0.15)) (justify left bottom) hide)
    )
    (property "MPN" "CC0201KRX6S5BB104" (at 103.505 86.36 0)
      (effects (font (size 1.27 1.27) (thickness 0.15)) (justify left bottom) hide)
    )
    (property "Val" "100n" (at 121.285 70.485 90)
      (effects (font (size 1.27 1.27) (thickness 0.15)) (justify left))
    )
    (property "License" "Apache-2.0" (at 98.425 86.36 0)
      (effects (font (size 1.27 1.27) (thickness 0.15)) (justify left bottom) hide)
    )
    (property "Author" "Antmicro" (at 95.885 86.36 0)
      (effects (font (size 1.27 1.27) (thickness 0.15)) (justify left bottom) hide)
    )
    (property "Voltage" "" (at 93.345 86.36 0)
      (effects (font (size 1.27 1.27)) (justify left bottom) hide)
    )
    (property "Dielectric" "" (at 90.805 86.36 0)
      (effects (font (size 1.27 1.27)) (justify left bottom) hide)
    )
    (pin "1")
    (pin "2")
    (instances
      (project "data-center-rdimm-ddr4-tester"
        (path ""
          (reference "C70") (unit 1)
        )
      )
    )
  )

  (symbol (lib_id "antmicropower:GND") (at 121.285 71.12 0) (mirror y) (unit 1)
    (in_bom yes) (on_board yes) (dnp no) (fields_autoplaced)
    (property "Reference" "#PWR0202" (at 121.285 77.47 0)
      (effects (font (size 1.27 1.27)) hide)
    )
    (property "Value" "GND" (at 121.285 76.2 0)
      (effects (font (size 1.27 1.27)))
    )
    (property "Footprint" "" (at 121.285 71.12 0)
      (effects (font (size 1.27 1.27)) hide)
    )
    (property "Datasheet" "" (at 121.285 71.12 0)
      (effects (font (size 1.27 1.27)) hide)
    )
    (property "Author" "Antmicro" (at 112.395 78.74 0)
      (effects (font (size 1.27 1.27) (thickness 0.15)) (justify left bottom) hide)
    )
    (property "License" "Apache-2.0" (at 112.395 81.28 0)
      (effects (font (size 1.27 1.27) (thickness 0.15)) (justify left bottom) hide)
    )
    (pin "1")
    (instances
      (project "data-center-rdimm-ddr4-tester"
        (path ""
          (reference "#PWR0202") (unit 1)
        )
      )
    )
  )

  (symbol (lib_id "antmicropower:GND") (at 122.555 206.375 0) (unit 1)
    (in_bom yes) (on_board yes) (dnp no) (fields_autoplaced)
    (property "Reference" "#PWR0256" (at 122.555 212.725 0)
      (effects (font (size 1.27 1.27)) hide)
    )
    (property "Value" "GND" (at 122.555 211.455 0)
      (effects (font (size 1.27 1.27)))
    )
    (property "Footprint" "" (at 122.555 206.375 0)
      (effects (font (size 1.27 1.27)) hide)
    )
    (property "Datasheet" "" (at 122.555 206.375 0)
      (effects (font (size 1.27 1.27)) hide)
    )
    (property "Author" "Antmicro" (at 131.445 213.995 0)
      (effects (font (size 1.27 1.27) (thickness 0.15)) (justify left bottom) hide)
    )
    (property "License" "Apache-2.0" (at 131.445 216.535 0)
      (effects (font (size 1.27 1.27) (thickness 0.15)) (justify left bottom) hide)
    )
    (pin "1")
    (instances
      (project "data-center-rdimm-ddr4-tester"
        (path ""
          (reference "#PWR0256") (unit 1)
        )
      )
    )
  )

  (symbol (lib_id "antmicropower:GND") (at 129.54 206.375 0) (unit 1)
    (in_bom yes) (on_board yes) (dnp no) (fields_autoplaced)
    (property "Reference" "#PWR0257" (at 129.54 212.725 0)
      (effects (font (size 1.27 1.27)) hide)
    )
    (property "Value" "GND" (at 129.54 211.455 0)
      (effects (font (size 1.27 1.27)))
    )
    (property "Footprint" "" (at 129.54 206.375 0)
      (effects (font (size 1.27 1.27)) hide)
    )
    (property "Datasheet" "" (at 129.54 206.375 0)
      (effects (font (size 1.27 1.27)) hide)
    )
    (property "Author" "Antmicro" (at 138.43 213.995 0)
      (effects (font (size 1.27 1.27) (thickness 0.15)) (justify left bottom) hide)
    )
    (property "License" "Apache-2.0" (at 138.43 216.535 0)
      (effects (font (size 1.27 1.27) (thickness 0.15)) (justify left bottom) hide)
    )
    (pin "1")
    (instances
      (project "data-center-rdimm-ddr4-tester"
        (path ""
          (reference "#PWR0257") (unit 1)
        )
      )
    )
  )

  (symbol (lib_id "antmicropower:GND") (at 135.89 206.375 0) (unit 1)
    (in_bom yes) (on_board yes) (dnp no) (fields_autoplaced)
    (property "Reference" "#PWR0258" (at 135.89 212.725 0)
      (effects (font (size 1.27 1.27)) hide)
    )
    (property "Value" "GND" (at 135.89 211.455 0)
      (effects (font (size 1.27 1.27)))
    )
    (property "Footprint" "" (at 135.89 206.375 0)
      (effects (font (size 1.27 1.27)) hide)
    )
    (property "Datasheet" "" (at 135.89 206.375 0)
      (effects (font (size 1.27 1.27)) hide)
    )
    (property "Author" "Antmicro" (at 144.78 213.995 0)
      (effects (font (size 1.27 1.27) (thickness 0.15)) (justify left bottom) hide)
    )
    (property "License" "Apache-2.0" (at 144.78 216.535 0)
      (effects (font (size 1.27 1.27) (thickness 0.15)) (justify left bottom) hide)
    )
    (pin "1")
    (instances
      (project "data-center-rdimm-ddr4-tester"
        (path ""
          (reference "#PWR0258") (unit 1)
        )
      )
    )
  )

  (symbol (lib_id "antmicropower:GND") (at 142.875 206.375 0) (unit 1)
    (in_bom yes) (on_board yes) (dnp no) (fields_autoplaced)
    (property "Reference" "#PWR0259" (at 142.875 212.725 0)
      (effects (font (size 1.27 1.27)) hide)
    )
    (property "Value" "GND" (at 142.875 211.455 0)
      (effects (font (size 1.27 1.27)))
    )
    (property "Footprint" "" (at 142.875 206.375 0)
      (effects (font (size 1.27 1.27)) hide)
    )
    (property "Datasheet" "" (at 142.875 206.375 0)
      (effects (font (size 1.27 1.27)) hide)
    )
    (property "Author" "Antmicro" (at 151.765 213.995 0)
      (effects (font (size 1.27 1.27) (thickness 0.15)) (justify left bottom) hide)
    )
    (property "License" "Apache-2.0" (at 151.765 216.535 0)
      (effects (font (size 1.27 1.27) (thickness 0.15)) (justify left bottom) hide)
    )
    (pin "1")
    (instances
      (project "data-center-rdimm-ddr4-tester"
        (path ""
          (reference "#PWR0259") (unit 1)
        )
      )
    )
  )

  (symbol (lib_id "antmicroCapacitorsmisc:C_100n_0201") (at 114.935 104.775 270) (unit 1)
    (in_bom yes) (on_board yes) (dnp no)
    (property "Reference" "C11" (at 114.935 105.41 90)
      (effects (font (size 1.524 1.524)) (justify left))
    )
    (property "Value" "C_100n_0201" (at 104.775 125.095 0)
      (effects (font (size 1.27 1.27) (thickness 0.15)) (justify left bottom) hide)
    )
    (property "Footprint" "antmicro-footprints:C_0201" (at 102.235 125.095 0)
      (effects (font (size 1.27 1.27) (thickness 0.15)) (justify left bottom) hide)
    )
    (property "Datasheet" " " (at 99.695 125.095 0)
      (effects (font (size 1.27 1.27) (thickness 0.15)) (justify left bottom) hide)
    )
    (property "Manufacturer" "Yaego" (at 94.615 125.095 0)
      (effects (font (size 1.27 1.27) (thickness 0.15)) (justify left bottom) hide)
    )
    (property "MPN" "CC0201KRX6S5BB104" (at 97.155 125.095 0)
      (effects (font (size 1.27 1.27) (thickness 0.15)) (justify left bottom) hide)
    )
    (property "Val" "100n" (at 114.935 109.22 90)
      (effects (font (size 1.27 1.27) (thickness 0.15)) (justify left))
    )
    (property "License" "Apache-2.0" (at 92.075 125.095 0)
      (effects (font (size 1.27 1.27) (thickness 0.15)) (justify left bottom) hide)
    )
    (property "Author" "Antmicro" (at 89.535 125.095 0)
      (effects (font (size 1.27 1.27) (thickness 0.15)) (justify left bottom) hide)
    )
    (property "Voltage" "" (at 86.995 125.095 0)
      (effects (font (size 1.27 1.27)) (justify left bottom) hide)
    )
    (property "Dielectric" "" (at 84.455 125.095 0)
      (effects (font (size 1.27 1.27)) (justify left bottom) hide)
    )
    (pin "1")
    (pin "2")
    (instances
      (project "data-center-rdimm-ddr4-tester"
        (path ""
          (reference "C11") (unit 1)
        )
      )
    )
  )

  (symbol (lib_id "antmicropower:GND") (at 114.935 109.855 0) (mirror y) (unit 1)
    (in_bom yes) (on_board yes) (dnp no) (fields_autoplaced)
    (property "Reference" "#PWR0205" (at 114.935 116.205 0)
      (effects (font (size 1.27 1.27)) hide)
    )
    (property "Value" "GND" (at 114.935 114.3 0)
      (effects (font (size 1.27 1.27)))
    )
    (property "Footprint" "" (at 114.935 109.855 0)
      (effects (font (size 1.27 1.27)) hide)
    )
    (property "Datasheet" "" (at 114.935 109.855 0)
      (effects (font (size 1.27 1.27)) hide)
    )
    (property "Author" "Antmicro" (at 106.045 117.475 0)
      (effects (font (size 1.27 1.27) (thickness 0.15)) (justify left bottom) hide)
    )
    (property "License" "Apache-2.0" (at 106.045 120.015 0)
      (effects (font (size 1.27 1.27) (thickness 0.15)) (justify left bottom) hide)
    )
    (pin "1")
    (instances
      (project "data-center-rdimm-ddr4-tester"
        (path ""
          (reference "#PWR0205") (unit 1)
        )
      )
    )
  )

  (symbol (lib_id "antmicroCapacitorsmisc:C_100n_0201") (at 121.92 104.775 270) (unit 1)
    (in_bom yes) (on_board yes) (dnp no)
    (property "Reference" "C48" (at 121.92 105.41 90)
      (effects (font (size 1.524 1.524)) (justify left))
    )
    (property "Value" "C_100n_0201" (at 111.76 125.095 0)
      (effects (font (size 1.27 1.27) (thickness 0.15)) (justify left bottom) hide)
    )
    (property "Footprint" "antmicro-footprints:C_0201" (at 109.22 125.095 0)
      (effects (font (size 1.27 1.27) (thickness 0.15)) (justify left bottom) hide)
    )
    (property "Datasheet" " " (at 106.68 125.095 0)
      (effects (font (size 1.27 1.27) (thickness 0.15)) (justify left bottom) hide)
    )
    (property "Manufacturer" "Yaego" (at 101.6 125.095 0)
      (effects (font (size 1.27 1.27) (thickness 0.15)) (justify left bottom) hide)
    )
    (property "MPN" "CC0201KRX6S5BB104" (at 104.14 125.095 0)
      (effects (font (size 1.27 1.27) (thickness 0.15)) (justify left bottom) hide)
    )
    (property "Val" "100n" (at 121.92 109.22 90)
      (effects (font (size 1.27 1.27) (thickness 0.15)) (justify left))
    )
    (property "License" "Apache-2.0" (at 99.06 125.095 0)
      (effects (font (size 1.27 1.27) (thickness 0.15)) (justify left bottom) hide)
    )
    (property "Author" "Antmicro" (at 96.52 125.095 0)
      (effects (font (size 1.27 1.27) (thickness 0.15)) (justify left bottom) hide)
    )
    (property "Voltage" "" (at 93.98 125.095 0)
      (effects (font (size 1.27 1.27)) (justify left bottom) hide)
    )
    (property "Dielectric" "" (at 91.44 125.095 0)
      (effects (font (size 1.27 1.27)) (justify left bottom) hide)
    )
    (pin "1")
    (pin "2")
    (instances
      (project "data-center-rdimm-ddr4-tester"
        (path ""
          (reference "C48") (unit 1)
        )
      )
    )
  )

  (symbol (lib_id "antmicropower:GND") (at 121.92 109.855 0) (mirror y) (unit 1)
    (in_bom yes) (on_board yes) (dnp no) (fields_autoplaced)
    (property "Reference" "#PWR0206" (at 121.92 116.205 0)
      (effects (font (size 1.27 1.27)) hide)
    )
    (property "Value" "GND" (at 121.92 114.3 0)
      (effects (font (size 1.27 1.27)))
    )
    (property "Footprint" "" (at 121.92 109.855 0)
      (effects (font (size 1.27 1.27)) hide)
    )
    (property "Datasheet" "" (at 121.92 109.855 0)
      (effects (font (size 1.27 1.27)) hide)
    )
    (property "Author" "Antmicro" (at 113.03 117.475 0)
      (effects (font (size 1.27 1.27) (thickness 0.15)) (justify left bottom) hide)
    )
    (property "License" "Apache-2.0" (at 113.03 120.015 0)
      (effects (font (size 1.27 1.27) (thickness 0.15)) (justify left bottom) hide)
    )
    (pin "1")
    (instances
      (project "data-center-rdimm-ddr4-tester"
        (path ""
          (reference "#PWR0206") (unit 1)
        )
      )
    )
  )

  (symbol (lib_id "antmicroCapacitorsmisc:C_100n_0201") (at 163.195 66.04 270) (unit 1)
    (in_bom yes) (on_board yes) (dnp no)
    (property "Reference" "C50" (at 163.195 66.675 90)
      (effects (font (size 1.524 1.524)) (justify left))
    )
    (property "Value" "C_100n_0201" (at 153.035 86.36 0)
      (effects (font (size 1.27 1.27) (thickness 0.15)) (justify left bottom) hide)
    )
    (property "Footprint" "antmicro-footprints:C_0201" (at 150.495 86.36 0)
      (effects (font (size 1.27 1.27) (thickness 0.15)) (justify left bottom) hide)
    )
    (property "Datasheet" " " (at 147.955 86.36 0)
      (effects (font (size 1.27 1.27) (thickness 0.15)) (justify left bottom) hide)
    )
    (property "Manufacturer" "Yaego" (at 142.875 86.36 0)
      (effects (font (size 1.27 1.27) (thickness 0.15)) (justify left bottom) hide)
    )
    (property "MPN" "CC0201KRX6S5BB104" (at 145.415 86.36 0)
      (effects (font (size 1.27 1.27) (thickness 0.15)) (justify left bottom) hide)
    )
    (property "Val" "100n" (at 163.195 70.485 90)
      (effects (font (size 1.27 1.27) (thickness 0.15)) (justify left))
    )
    (property "License" "Apache-2.0" (at 140.335 86.36 0)
      (effects (font (size 1.27 1.27) (thickness 0.15)) (justify left bottom) hide)
    )
    (property "Author" "Antmicro" (at 137.795 86.36 0)
      (effects (font (size 1.27 1.27) (thickness 0.15)) (justify left bottom) hide)
    )
    (property "Voltage" "" (at 135.255 86.36 0)
      (effects (font (size 1.27 1.27)) (justify left bottom) hide)
    )
    (property "Dielectric" "" (at 132.715 86.36 0)
      (effects (font (size 1.27 1.27)) (justify left bottom) hide)
    )
    (pin "1")
    (pin "2")
    (instances
      (project "data-center-rdimm-ddr4-tester"
        (path ""
          (reference "C50") (unit 1)
        )
      )
    )
  )

  (symbol (lib_id "antmicropower:GND") (at 163.195 71.12 0) (mirror y) (unit 1)
    (in_bom yes) (on_board yes) (dnp no) (fields_autoplaced)
    (property "Reference" "#PWR0207" (at 163.195 77.47 0)
      (effects (font (size 1.27 1.27)) hide)
    )
    (property "Value" "GND" (at 163.195 76.2 0)
      (effects (font (size 1.27 1.27)))
    )
    (property "Footprint" "" (at 163.195 71.12 0)
      (effects (font (size 1.27 1.27)) hide)
    )
    (property "Datasheet" "" (at 163.195 71.12 0)
      (effects (font (size 1.27 1.27)) hide)
    )
    (property "Author" "Antmicro" (at 154.305 78.74 0)
      (effects (font (size 1.27 1.27) (thickness 0.15)) (justify left bottom) hide)
    )
    (property "License" "Apache-2.0" (at 154.305 81.28 0)
      (effects (font (size 1.27 1.27) (thickness 0.15)) (justify left bottom) hide)
    )
    (pin "1")
    (instances
      (project "data-center-rdimm-ddr4-tester"
        (path ""
          (reference "#PWR0207") (unit 1)
        )
      )
    )
  )

  (symbol (lib_id "antmicroCapacitorsmisc:C_100n_0201") (at 170.18 66.04 270) (unit 1)
    (in_bom yes) (on_board yes) (dnp no)
    (property "Reference" "C52" (at 170.18 66.675 90)
      (effects (font (size 1.524 1.524)) (justify left))
    )
    (property "Value" "C_100n_0201" (at 160.02 86.36 0)
      (effects (font (size 1.27 1.27) (thickness 0.15)) (justify left bottom) hide)
    )
    (property "Footprint" "antmicro-footprints:C_0201" (at 157.48 86.36 0)
      (effects (font (size 1.27 1.27) (thickness 0.15)) (justify left bottom) hide)
    )
    (property "Datasheet" " " (at 154.94 86.36 0)
      (effects (font (size 1.27 1.27) (thickness 0.15)) (justify left bottom) hide)
    )
    (property "Manufacturer" "Yaego" (at 149.86 86.36 0)
      (effects (font (size 1.27 1.27) (thickness 0.15)) (justify left bottom) hide)
    )
    (property "MPN" "CC0201KRX6S5BB104" (at 152.4 86.36 0)
      (effects (font (size 1.27 1.27) (thickness 0.15)) (justify left bottom) hide)
    )
    (property "Val" "100n" (at 170.18 70.485 90)
      (effects (font (size 1.27 1.27) (thickness 0.15)) (justify left))
    )
    (property "License" "Apache-2.0" (at 147.32 86.36 0)
      (effects (font (size 1.27 1.27) (thickness 0.15)) (justify left bottom) hide)
    )
    (property "Author" "Antmicro" (at 144.78 86.36 0)
      (effects (font (size 1.27 1.27) (thickness 0.15)) (justify left bottom) hide)
    )
    (property "Voltage" "" (at 142.24 86.36 0)
      (effects (font (size 1.27 1.27)) (justify left bottom) hide)
    )
    (property "Dielectric" "" (at 139.7 86.36 0)
      (effects (font (size 1.27 1.27)) (justify left bottom) hide)
    )
    (pin "1")
    (pin "2")
    (instances
      (project "data-center-rdimm-ddr4-tester"
        (path ""
          (reference "C52") (unit 1)
        )
      )
    )
  )

  (symbol (lib_id "antmicropower:GND") (at 170.18 71.12 0) (mirror y) (unit 1)
    (in_bom yes) (on_board yes) (dnp no) (fields_autoplaced)
    (property "Reference" "#PWR0210" (at 170.18 77.47 0)
      (effects (font (size 1.27 1.27)) hide)
    )
    (property "Value" "GND" (at 170.18 76.2 0)
      (effects (font (size 1.27 1.27)))
    )
    (property "Footprint" "" (at 170.18 71.12 0)
      (effects (font (size 1.27 1.27)) hide)
    )
    (property "Datasheet" "" (at 170.18 71.12 0)
      (effects (font (size 1.27 1.27)) hide)
    )
    (property "Author" "Antmicro" (at 161.29 78.74 0)
      (effects (font (size 1.27 1.27) (thickness 0.15)) (justify left bottom) hide)
    )
    (property "License" "Apache-2.0" (at 161.29 81.28 0)
      (effects (font (size 1.27 1.27) (thickness 0.15)) (justify left bottom) hide)
    )
    (pin "1")
    (instances
      (project "data-center-rdimm-ddr4-tester"
        (path ""
          (reference "#PWR0210") (unit 1)
        )
      )
    )
  )

  (symbol (lib_id "antmicroCapacitorsmisc:C_100n_0201") (at 177.165 66.04 270) (unit 1)
    (in_bom yes) (on_board yes) (dnp no)
    (property "Reference" "C54" (at 177.165 66.675 90)
      (effects (font (size 1.524 1.524)) (justify left))
    )
    (property "Value" "C_100n_0201" (at 167.005 86.36 0)
      (effects (font (size 1.27 1.27) (thickness 0.15)) (justify left bottom) hide)
    )
    (property "Footprint" "antmicro-footprints:C_0201" (at 164.465 86.36 0)
      (effects (font (size 1.27 1.27) (thickness 0.15)) (justify left bottom) hide)
    )
    (property "Datasheet" " " (at 161.925 86.36 0)
      (effects (font (size 1.27 1.27) (thickness 0.15)) (justify left bottom) hide)
    )
    (property "Manufacturer" "Yaego" (at 156.845 86.36 0)
      (effects (font (size 1.27 1.27) (thickness 0.15)) (justify left bottom) hide)
    )
    (property "MPN" "CC0201KRX6S5BB104" (at 159.385 86.36 0)
      (effects (font (size 1.27 1.27) (thickness 0.15)) (justify left bottom) hide)
    )
    (property "Val" "100n" (at 177.165 70.485 90)
      (effects (font (size 1.27 1.27) (thickness 0.15)) (justify left))
    )
    (property "License" "Apache-2.0" (at 154.305 86.36 0)
      (effects (font (size 1.27 1.27) (thickness 0.15)) (justify left bottom) hide)
    )
    (property "Author" "Antmicro" (at 151.765 86.36 0)
      (effects (font (size 1.27 1.27) (thickness 0.15)) (justify left bottom) hide)
    )
    (property "Voltage" "" (at 149.225 86.36 0)
      (effects (font (size 1.27 1.27)) (justify left bottom) hide)
    )
    (property "Dielectric" "" (at 146.685 86.36 0)
      (effects (font (size 1.27 1.27)) (justify left bottom) hide)
    )
    (pin "1")
    (pin "2")
    (instances
      (project "data-center-rdimm-ddr4-tester"
        (path ""
          (reference "C54") (unit 1)
        )
      )
    )
  )

  (symbol (lib_id "antmicropower:GND") (at 177.165 71.12 0) (mirror y) (unit 1)
    (in_bom yes) (on_board yes) (dnp no) (fields_autoplaced)
    (property "Reference" "#PWR0229" (at 177.165 77.47 0)
      (effects (font (size 1.27 1.27)) hide)
    )
    (property "Value" "GND" (at 177.165 76.2 0)
      (effects (font (size 1.27 1.27)))
    )
    (property "Footprint" "" (at 177.165 71.12 0)
      (effects (font (size 1.27 1.27)) hide)
    )
    (property "Datasheet" "" (at 177.165 71.12 0)
      (effects (font (size 1.27 1.27)) hide)
    )
    (property "Author" "Antmicro" (at 168.275 78.74 0)
      (effects (font (size 1.27 1.27) (thickness 0.15)) (justify left bottom) hide)
    )
    (property "License" "Apache-2.0" (at 168.275 81.28 0)
      (effects (font (size 1.27 1.27) (thickness 0.15)) (justify left bottom) hide)
    )
    (pin "1")
    (instances
      (project "data-center-rdimm-ddr4-tester"
        (path ""
          (reference "#PWR0229") (unit 1)
        )
      )
    )
  )

  (symbol (lib_id "antmicropower:GND") (at 31.115 109.855 0) (mirror y) (unit 1)
    (in_bom yes) (on_board yes) (dnp no) (fields_autoplaced)
    (property "Reference" "#PWR0231" (at 31.115 116.205 0)
      (effects (font (size 1.27 1.27)) hide)
    )
    (property "Value" "GND" (at 31.115 114.3 0)
      (effects (font (size 1.27 1.27)))
    )
    (property "Footprint" "" (at 31.115 109.855 0)
      (effects (font (size 1.27 1.27)) hide)
    )
    (property "Datasheet" "" (at 31.115 109.855 0)
      (effects (font (size 1.27 1.27)) hide)
    )
    (property "Author" "Antmicro" (at 22.225 117.475 0)
      (effects (font (size 1.27 1.27) (thickness 0.15)) (justify left bottom) hide)
    )
    (property "License" "Apache-2.0" (at 22.225 120.015 0)
      (effects (font (size 1.27 1.27) (thickness 0.15)) (justify left bottom) hide)
    )
    (pin "1")
    (instances
      (project "data-center-rdimm-ddr4-tester"
        (path ""
          (reference "#PWR0231") (unit 1)
        )
      )
    )
  )

  (symbol (lib_id "antmicropower:GND") (at 38.1 109.855 0) (mirror y) (unit 1)
    (in_bom yes) (on_board yes) (dnp no) (fields_autoplaced)
    (property "Reference" "#PWR0232" (at 38.1 116.205 0)
      (effects (font (size 1.27 1.27)) hide)
    )
    (property "Value" "GND" (at 38.1 114.3 0)
      (effects (font (size 1.27 1.27)))
    )
    (property "Footprint" "" (at 38.1 109.855 0)
      (effects (font (size 1.27 1.27)) hide)
    )
    (property "Datasheet" "" (at 38.1 109.855 0)
      (effects (font (size 1.27 1.27)) hide)
    )
    (property "Author" "Antmicro" (at 29.21 117.475 0)
      (effects (font (size 1.27 1.27) (thickness 0.15)) (justify left bottom) hide)
    )
    (property "License" "Apache-2.0" (at 29.21 120.015 0)
      (effects (font (size 1.27 1.27) (thickness 0.15)) (justify left bottom) hide)
    )
    (pin "1")
    (instances
      (project "data-center-rdimm-ddr4-tester"
        (path ""
          (reference "#PWR0232") (unit 1)
        )
      )
    )
  )

  (symbol (lib_id "antmicropower:GND") (at 45.085 109.855 0) (mirror y) (unit 1)
    (in_bom yes) (on_board yes) (dnp no) (fields_autoplaced)
    (property "Reference" "#PWR0237" (at 45.085 116.205 0)
      (effects (font (size 1.27 1.27)) hide)
    )
    (property "Value" "GND" (at 45.085 114.3 0)
      (effects (font (size 1.27 1.27)))
    )
    (property "Footprint" "" (at 45.085 109.855 0)
      (effects (font (size 1.27 1.27)) hide)
    )
    (property "Datasheet" "" (at 45.085 109.855 0)
      (effects (font (size 1.27 1.27)) hide)
    )
    (property "Author" "Antmicro" (at 36.195 117.475 0)
      (effects (font (size 1.27 1.27) (thickness 0.15)) (justify left bottom) hide)
    )
    (property "License" "Apache-2.0" (at 36.195 120.015 0)
      (effects (font (size 1.27 1.27) (thickness 0.15)) (justify left bottom) hide)
    )
    (pin "1")
    (instances
      (project "data-center-rdimm-ddr4-tester"
        (path ""
          (reference "#PWR0237") (unit 1)
        )
      )
    )
  )

  (symbol (lib_id "antmicropower:GND") (at 52.07 109.855 0) (mirror y) (unit 1)
    (in_bom yes) (on_board yes) (dnp no) (fields_autoplaced)
    (property "Reference" "#PWR0238" (at 52.07 116.205 0)
      (effects (font (size 1.27 1.27)) hide)
    )
    (property "Value" "GND" (at 52.07 114.3 0)
      (effects (font (size 1.27 1.27)))
    )
    (property "Footprint" "" (at 52.07 109.855 0)
      (effects (font (size 1.27 1.27)) hide)
    )
    (property "Datasheet" "" (at 52.07 109.855 0)
      (effects (font (size 1.27 1.27)) hide)
    )
    (property "Author" "Antmicro" (at 43.18 117.475 0)
      (effects (font (size 1.27 1.27) (thickness 0.15)) (justify left bottom) hide)
    )
    (property "License" "Apache-2.0" (at 43.18 120.015 0)
      (effects (font (size 1.27 1.27) (thickness 0.15)) (justify left bottom) hide)
    )
    (pin "1")
    (instances
      (project "data-center-rdimm-ddr4-tester"
        (path ""
          (reference "#PWR0238") (unit 1)
        )
      )
    )
  )

  (symbol (lib_id "antmicropower:GND") (at 59.055 109.855 0) (mirror y) (unit 1)
    (in_bom yes) (on_board yes) (dnp no) (fields_autoplaced)
    (property "Reference" "#PWR0239" (at 59.055 116.205 0)
      (effects (font (size 1.27 1.27)) hide)
    )
    (property "Value" "GND" (at 59.055 114.3 0)
      (effects (font (size 1.27 1.27)))
    )
    (property "Footprint" "" (at 59.055 109.855 0)
      (effects (font (size 1.27 1.27)) hide)
    )
    (property "Datasheet" "" (at 59.055 109.855 0)
      (effects (font (size 1.27 1.27)) hide)
    )
    (property "Author" "Antmicro" (at 50.165 117.475 0)
      (effects (font (size 1.27 1.27) (thickness 0.15)) (justify left bottom) hide)
    )
    (property "License" "Apache-2.0" (at 50.165 120.015 0)
      (effects (font (size 1.27 1.27) (thickness 0.15)) (justify left bottom) hide)
    )
    (pin "1")
    (instances
      (project "data-center-rdimm-ddr4-tester"
        (path ""
          (reference "#PWR0239") (unit 1)
        )
      )
    )
  )

  (symbol (lib_id "antmicropower:GND") (at 142.24 71.12 0) (mirror y) (unit 1)
    (in_bom yes) (on_board yes) (dnp no) (fields_autoplaced)
    (property "Reference" "#PWR0240" (at 142.24 77.47 0)
      (effects (font (size 1.27 1.27)) hide)
    )
    (property "Value" "GND" (at 142.24 76.2 0)
      (effects (font (size 1.27 1.27)))
    )
    (property "Footprint" "" (at 142.24 71.12 0)
      (effects (font (size 1.27 1.27)) hide)
    )
    (property "Datasheet" "" (at 142.24 71.12 0)
      (effects (font (size 1.27 1.27)) hide)
    )
    (property "Author" "Antmicro" (at 133.35 78.74 0)
      (effects (font (size 1.27 1.27) (thickness 0.15)) (justify left bottom) hide)
    )
    (property "License" "Apache-2.0" (at 133.35 81.28 0)
      (effects (font (size 1.27 1.27) (thickness 0.15)) (justify left bottom) hide)
    )
    (pin "1")
    (instances
      (project "data-center-rdimm-ddr4-tester"
        (path ""
          (reference "#PWR0240") (unit 1)
        )
      )
    )
  )

  (symbol (lib_id "antmicropower:GND") (at 149.225 71.12 0) (mirror y) (unit 1)
    (in_bom yes) (on_board yes) (dnp no) (fields_autoplaced)
    (property "Reference" "#PWR0241" (at 149.225 77.47 0)
      (effects (font (size 1.27 1.27)) hide)
    )
    (property "Value" "GND" (at 149.225 76.2 0)
      (effects (font (size 1.27 1.27)))
    )
    (property "Footprint" "" (at 149.225 71.12 0)
      (effects (font (size 1.27 1.27)) hide)
    )
    (property "Datasheet" "" (at 149.225 71.12 0)
      (effects (font (size 1.27 1.27)) hide)
    )
    (property "Author" "Antmicro" (at 140.335 78.74 0)
      (effects (font (size 1.27 1.27) (thickness 0.15)) (justify left bottom) hide)
    )
    (property "License" "Apache-2.0" (at 140.335 81.28 0)
      (effects (font (size 1.27 1.27) (thickness 0.15)) (justify left bottom) hide)
    )
    (pin "1")
    (instances
      (project "data-center-rdimm-ddr4-tester"
        (path ""
          (reference "#PWR0241") (unit 1)
        )
      )
    )
  )

  (symbol (lib_id "antmicropower:GND") (at 156.21 71.12 0) (mirror y) (unit 1)
    (in_bom yes) (on_board yes) (dnp no) (fields_autoplaced)
    (property "Reference" "#PWR0242" (at 156.21 77.47 0)
      (effects (font (size 1.27 1.27)) hide)
    )
    (property "Value" "GND" (at 156.21 76.2 0)
      (effects (font (size 1.27 1.27)))
    )
    (property "Footprint" "" (at 156.21 71.12 0)
      (effects (font (size 1.27 1.27)) hide)
    )
    (property "Datasheet" "" (at 156.21 71.12 0)
      (effects (font (size 1.27 1.27)) hide)
    )
    (property "Author" "Antmicro" (at 147.32 78.74 0)
      (effects (font (size 1.27 1.27) (thickness 0.15)) (justify left bottom) hide)
    )
    (property "License" "Apache-2.0" (at 147.32 81.28 0)
      (effects (font (size 1.27 1.27) (thickness 0.15)) (justify left bottom) hide)
    )
    (pin "1")
    (instances
      (project "data-center-rdimm-ddr4-tester"
        (path ""
          (reference "#PWR0242") (unit 1)
        )
      )
    )
  )

  (symbol (lib_id "antmicroCapacitorsmisc:C_100n_0201") (at 128.27 135.255 270) (unit 1)
    (in_bom yes) (on_board yes) (dnp no)
    (property "Reference" "C21" (at 128.27 135.89 90)
      (effects (font (size 1.524 1.524)) (justify left))
    )
    (property "Value" "C_100n_0201" (at 118.11 155.575 0)
      (effects (font (size 1.27 1.27) (thickness 0.15)) (justify left bottom) hide)
    )
    (property "Footprint" "antmicro-footprints:C_0201" (at 115.57 155.575 0)
      (effects (font (size 1.27 1.27) (thickness 0.15)) (justify left bottom) hide)
    )
    (property "Datasheet" " " (at 113.03 155.575 0)
      (effects (font (size 1.27 1.27) (thickness 0.15)) (justify left bottom) hide)
    )
    (property "Manufacturer" "Yaego" (at 107.95 155.575 0)
      (effects (font (size 1.27 1.27) (thickness 0.15)) (justify left bottom) hide)
    )
    (property "MPN" "CC0201KRX6S5BB104" (at 110.49 155.575 0)
      (effects (font (size 1.27 1.27) (thickness 0.15)) (justify left bottom) hide)
    )
    (property "Val" "100n" (at 128.27 139.7 90)
      (effects (font (size 1.27 1.27) (thickness 0.15)) (justify left))
    )
    (property "License" "Apache-2.0" (at 105.41 155.575 0)
      (effects (font (size 1.27 1.27) (thickness 0.15)) (justify left bottom) hide)
    )
    (property "Author" "Antmicro" (at 102.87 155.575 0)
      (effects (font (size 1.27 1.27) (thickness 0.15)) (justify left bottom) hide)
    )
    (property "Voltage" "" (at 100.33 155.575 0)
      (effects (font (size 1.27 1.27)) (justify left bottom) hide)
    )
    (property "Dielectric" "" (at 97.79 155.575 0)
      (effects (font (size 1.27 1.27)) (justify left bottom) hide)
    )
    (pin "1")
    (pin "2")
    (instances
      (project "data-center-rdimm-ddr4-tester"
        (path ""
          (reference "C21") (unit 1)
        )
      )
    )
  )

  (symbol (lib_id "antmicropower:GND") (at 128.27 140.335 0) (unit 1)
    (in_bom yes) (on_board yes) (dnp no) (fields_autoplaced)
    (property "Reference" "#PWR048" (at 128.27 146.685 0)
      (effects (font (size 1.27 1.27)) hide)
    )
    (property "Value" "GND" (at 128.27 145.415 0)
      (effects (font (size 1.27 1.27)))
    )
    (property "Footprint" "" (at 128.27 140.335 0)
      (effects (font (size 1.27 1.27)) hide)
    )
    (property "Datasheet" "" (at 128.27 140.335 0)
      (effects (font (size 1.27 1.27)) hide)
    )
    (property "Author" "Antmicro" (at 137.16 147.955 0)
      (effects (font (size 1.27 1.27) (thickness 0.15)) (justify left bottom) hide)
    )
    (property "License" "Apache-2.0" (at 137.16 150.495 0)
      (effects (font (size 1.27 1.27) (thickness 0.15)) (justify left bottom) hide)
    )
    (pin "1")
    (instances
      (project "data-center-rdimm-ddr4-tester"
        (path ""
          (reference "#PWR048") (unit 1)
        )
      )
    )
  )

  (symbol (lib_id "antmicroCapacitorsmisc:C_100n_0201") (at 135.255 135.255 270) (unit 1)
    (in_bom yes) (on_board yes) (dnp no)
    (property "Reference" "C143" (at 135.255 135.89 90)
      (effects (font (size 1.524 1.524)) (justify left))
    )
    (property "Value" "C_100n_0201" (at 125.095 155.575 0)
      (effects (font (size 1.27 1.27) (thickness 0.15)) (justify left bottom) hide)
    )
    (property "Footprint" "antmicro-footprints:C_0201" (at 122.555 155.575 0)
      (effects (font (size 1.27 1.27) (thickness 0.15)) (justify left bottom) hide)
    )
    (property "Datasheet" " " (at 120.015 155.575 0)
      (effects (font (size 1.27 1.27) (thickness 0.15)) (justify left bottom) hide)
    )
    (property "Manufacturer" "Yaego" (at 114.935 155.575 0)
      (effects (font (size 1.27 1.27) (thickness 0.15)) (justify left bottom) hide)
    )
    (property "MPN" "CC0201KRX6S5BB104" (at 117.475 155.575 0)
      (effects (font (size 1.27 1.27) (thickness 0.15)) (justify left bottom) hide)
    )
    (property "Val" "100n" (at 135.255 139.7 90)
      (effects (font (size 1.27 1.27) (thickness 0.15)) (justify left))
    )
    (property "License" "Apache-2.0" (at 112.395 155.575 0)
      (effects (font (size 1.27 1.27) (thickness 0.15)) (justify left bottom) hide)
    )
    (property "Author" "Antmicro" (at 109.855 155.575 0)
      (effects (font (size 1.27 1.27) (thickness 0.15)) (justify left bottom) hide)
    )
    (property "Voltage" "" (at 107.315 155.575 0)
      (effects (font (size 1.27 1.27)) (justify left bottom) hide)
    )
    (property "Dielectric" "" (at 104.775 155.575 0)
      (effects (font (size 1.27 1.27)) (justify left bottom) hide)
    )
    (pin "1")
    (pin "2")
    (instances
      (project "data-center-rdimm-ddr4-tester"
        (path ""
          (reference "C143") (unit 1)
        )
      )
    )
  )

  (symbol (lib_id "antmicropower:GND") (at 135.255 140.335 0) (unit 1)
    (in_bom yes) (on_board yes) (dnp no) (fields_autoplaced)
    (property "Reference" "#PWR049" (at 135.255 146.685 0)
      (effects (font (size 1.27 1.27)) hide)
    )
    (property "Value" "GND" (at 135.255 145.415 0)
      (effects (font (size 1.27 1.27)))
    )
    (property "Footprint" "" (at 135.255 140.335 0)
      (effects (font (size 1.27 1.27)) hide)
    )
    (property "Datasheet" "" (at 135.255 140.335 0)
      (effects (font (size 1.27 1.27)) hide)
    )
    (property "Author" "Antmicro" (at 144.145 147.955 0)
      (effects (font (size 1.27 1.27) (thickness 0.15)) (justify left bottom) hide)
    )
    (property "License" "Apache-2.0" (at 144.145 150.495 0)
      (effects (font (size 1.27 1.27) (thickness 0.15)) (justify left bottom) hide)
    )
    (pin "1")
    (instances
      (project "data-center-rdimm-ddr4-tester"
        (path ""
          (reference "#PWR049") (unit 1)
        )
      )
    )
  )

  (symbol (lib_id "antmicroMicrocontrollers:XC7K160T-FFG676") (at 268.605 57.785 0) (unit 10)
    (in_bom yes) (on_board yes) (dnp no) (fields_autoplaced)
    (property "Reference" "U15" (at 290.83 49.53 0)
      (effects (font (size 1.27 1.27)))
    )
    (property "Value" "XC7K160T-FFG676" (at 290.83 52.07 0)
      (effects (font (size 1.27 1.27) (thickness 0.15)))
    )
    (property "Footprint" "antmicro-footprints:BGA-676_27x27mm_Layout26x26_P1X1mm" (at 337.185 60.325 0)
      (effects (font (size 1.27 1.27) (thickness 0.15)) (justify left bottom) hide)
    )
    (property "Datasheet" "https://docs.xilinx.com/v/u/en-US/ds180_7Series_Overview" (at 337.185 62.865 0)
      (effects (font (size 1.27 1.27) (thickness 0.15)) (justify left bottom) hide)
    )
    (property "MPN" "XC7K160T-FFG676" (at 268.605 57.785 0)
      (effects (font (size 1.27 1.27)) hide)
    )
    (property "Author" "Antmicro" (at 337.185 65.405 0)
      (effects (font (size 1.27 1.27) (thickness 0.15)) (justify left bottom) hide)
    )
    (property "License" "Apache-2.0" (at 337.185 67.945 0)
      (effects (font (size 1.27 1.27) (thickness 0.15)) (justify left bottom) hide)
    )
    (property "Manufacturer" "AMD-Xilinx" (at 268.605 57.785 0)
      (effects (font (size 1.27 1.27)) hide)
    )
    (pin "AA21")
    (pin "AA22")
    (pin "AA23")
    (pin "AA24")
    (pin "AA25")
    (pin "AB21")
    (pin "AB22")
    (pin "AB24")
    (pin "AB25")
    (pin "AB26")
    (pin "AC21")
    (pin "AC22")
    (pin "AC23")
    (pin "AC24")
    (pin "AC25")
    (pin "AC26")
    (pin "AD21")
    (pin "AD22")
    (pin "AD23")
    (pin "AD24")
    (pin "AD25")
    (pin "AD26")
    (pin "AE21")
    (pin "AE22")
    (pin "AE23")
    (pin "AE25")
    (pin "AE26")
    (pin "AF22")
    (pin "AF23")
    (pin "AF24")
    (pin "AF25")
    (pin "AF26")
    (pin "U21")
    (pin "U22")
    (pin "U23")
    (pin "U24")
    (pin "U25")
    (pin "U26")
    (pin "V20")
    (pin "V21")
    (pin "V22")
    (pin "V23")
    (pin "V24")
    (pin "V26")
    (pin "W20")
    (pin "W21")
    (pin "W23")
    (pin "W24")
    (pin "W25")
    (pin "W26")
    (pin "Y20")
    (pin "Y21")
    (pin "Y22")
    (pin "Y23")
    (pin "Y24")
    (pin "Y25")
    (pin "Y26")
    (pin "K24")
    (pin "K25")
    (pin "K26")
    (pin "L24")
    (pin "L25")
    (pin "M19")
    (pin "M20")
    (pin "M21")
    (pin "M22")
    (pin "M24")
    (pin "M25")
    (pin "M26")
    (pin "N16")
    (pin "N17")
    (pin "N18")
    (pin "N19")
    (pin "N21")
    (pin "N22")
    (pin "N23")
    (pin "N24")
    (pin "N25")
    (pin "N26")
    (pin "P16")
    (pin "P18")
    (pin "P19")
    (pin "P20")
    (pin "P21")
    (pin "P22")
    (pin "P23")
    (pin "P24")
    (pin "P25")
    (pin "P26")
    (pin "R16")
    (pin "R17")
    (pin "R18")
    (pin "R19")
    (pin "R20")
    (pin "R21")
    (pin "R22")
    (pin "R23")
    (pin "R25")
    (pin "R26")
    (pin "T16")
    (pin "T17")
    (pin "T18")
    (pin "T19")
    (pin "T20")
    (pin "T22")
    (pin "T23")
    (pin "T24")
    (pin "T25")
    (pin "T26")
    (pin "U16")
    (pin "U17")
    (pin "U19")
    (pin "U20")
    (pin "A20")
    (pin "A21")
    (pin "A22")
    (pin "A23")
    (pin "A24")
    (pin "A25")
    (pin "B20")
    (pin "B21")
    (pin "B22")
    (pin "B24")
    (pin "B25")
    (pin "B26")
    (pin "C21")
    (pin "C22")
    (pin "C23")
    (pin "C24")
    (pin "C25")
    (pin "C26")
    (pin "D21")
    (pin "D22")
    (pin "D23")
    (pin "D24")
    (pin "D25")
    (pin "D26")
    (pin "E21")
    (pin "E22")
    (pin "E23")
    (pin "E25")
    (pin "E26")
    (pin "F22")
    (pin "F23")
    (pin "F24")
    (pin "F25")
    (pin "F26")
    (pin "G21")
    (pin "G22")
    (pin "G23")
    (pin "G24")
    (pin "G25")
    (pin "G26")
    (pin "H21")
    (pin "H22")
    (pin "H23")
    (pin "H24")
    (pin "H26")
    (pin "J21")
    (pin "J23")
    (pin "J24")
    (pin "J25")
    (pin "J26")
    (pin "K21")
    (pin "K22")
    (pin "K23")
    (pin "L21")
    (pin "L22")
    (pin "L23")
    (pin "A17")
    (pin "A18")
    (pin "A19")
    (pin "B16")
    (pin "B17")
    (pin "B18")
    (pin "B19")
    (pin "C16")
    (pin "C17")
    (pin "C18")
    (pin "C19")
    (pin "D15")
    (pin "D16")
    (pin "D18")
    (pin "D19")
    (pin "D20")
    (pin "E15")
    (pin "E16")
    (pin "E17")
    (pin "E18")
    (pin "E19")
    (pin "E20")
    (pin "F15")
    (pin "F16")
    (pin "F17")
    (pin "F18")
    (pin "F19")
    (pin "F20")
    (pin "G15")
    (pin "G16")
    (pin "G17")
    (pin "G19")
    (pin "G20")
    (pin "H16")
    (pin "H17")
    (pin "H18")
    (pin "H19")
    (pin "H20")
    (pin "J15")
    (pin "J16")
    (pin "J17")
    (pin "J18")
    (pin "J19")
    (pin "J20")
    (pin "K15")
    (pin "K16")
    (pin "K17")
    (pin "K18")
    (pin "K20")
    (pin "L17")
    (pin "L18")
    (pin "L19")
    (pin "L20")
    (pin "M16")
    (pin "M17")
    (pin "M18")
    (pin "A10")
    (pin "A11")
    (pin "A12")
    (pin "A13")
    (pin "A14")
    (pin "A15")
    (pin "A8")
    (pin "A9")
    (pin "B10")
    (pin "B11")
    (pin "B12")
    (pin "B14")
    (pin "B15")
    (pin "B8")
    (pin "B9")
    (pin "C11")
    (pin "C12")
    (pin "C13")
    (pin "C14")
    (pin "C15")
    (pin "C9")
    (pin "D10")
    (pin "D11")
    (pin "D12")
    (pin "D13")
    (pin "D14")
    (pin "D8")
    (pin "D9")
    (pin "E10")
    (pin "E11")
    (pin "E12")
    (pin "E13")
    (pin "E9")
    (pin "F10")
    (pin "F12")
    (pin "F13")
    (pin "F14")
    (pin "F8")
    (pin "F9")
    (pin "G10")
    (pin "G11")
    (pin "G12")
    (pin "G13")
    (pin "G14")
    (pin "G9")
    (pin "H10")
    (pin "H11")
    (pin "H12")
    (pin "H13")
    (pin "H14")
    (pin "H8")
    (pin "H9")
    (pin "J10")
    (pin "J11")
    (pin "J13")
    (pin "J14")
    (pin "J8")
    (pin "AA14")
    (pin "AA15")
    (pin "AA17")
    (pin "AA18")
    (pin "AA19")
    (pin "AA20")
    (pin "AB14")
    (pin "AB15")
    (pin "AB16")
    (pin "AB17")
    (pin "AB18")
    (pin "AB19")
    (pin "AB20")
    (pin "AC14")
    (pin "AC15")
    (pin "AC16")
    (pin "AC17")
    (pin "AC18")
    (pin "AC19")
    (pin "AD14")
    (pin "AD15")
    (pin "AD16")
    (pin "AD18")
    (pin "AD19")
    (pin "AD20")
    (pin "AE15")
    (pin "AE16")
    (pin "AE17")
    (pin "AE18")
    (pin "AE19")
    (pin "AE20")
    (pin "AF14")
    (pin "AF15")
    (pin "AF16")
    (pin "AF17")
    (pin "AF18")
    (pin "AF19")
    (pin "AF20")
    (pin "V13")
    (pin "V14")
    (pin "V16")
    (pin "V17")
    (pin "V18")
    (pin "V19")
    (pin "W13")
    (pin "W14")
    (pin "W15")
    (pin "W16")
    (pin "W17")
    (pin "W18")
    (pin "W19")
    (pin "Y14")
    (pin "Y15")
    (pin "Y16")
    (pin "Y17")
    (pin "Y18")
    (pin "AA10")
    (pin "AA11")
    (pin "AA12")
    (pin "AA13")
    (pin "AA7")
    (pin "AA8")
    (pin "AA9")
    (pin "AB10")
    (pin "AB11")
    (pin "AB12")
    (pin "AB7")
    (pin "AB8")
    (pin "AB9")
    (pin "AC11")
    (pin "AC12")
    (pin "AC13")
    (pin "AC7")
    (pin "AC8")
    (pin "AC9")
    (pin "AD10")
    (pin "AD11")
    (pin "AD12")
    (pin "AD13")
    (pin "AD8")
    (pin "AD9")
    (pin "AE10")
    (pin "AE11")
    (pin "AE12")
    (pin "AE13")
    (pin "AE7")
    (pin "AE8")
    (pin "AE9")
    (pin "AF10")
    (pin "AF12")
    (pin "AF13")
    (pin "AF7")
    (pin "AF8")
    (pin "AF9")
    (pin "U9")
    (pin "V10")
    (pin "V11")
    (pin "V12")
    (pin "V7")
    (pin "V8")
    (pin "V9")
    (pin "W10")
    (pin "W11")
    (pin "W7")
    (pin "W8")
    (pin "W9")
    (pin "Y10")
    (pin "Y11")
    (pin "Y12")
    (pin "Y13")
    (pin "Y7")
    (pin "Y8")
    (pin "AA1")
    (pin "AA2")
    (pin "AA3")
    (pin "AA4")
    (pin "AA5")
    (pin "AB1")
    (pin "AB2")
    (pin "AB4")
    (pin "AB5")
    (pin "AB6")
    (pin "AC1")
    (pin "AC2")
    (pin "AC3")
    (pin "AC4")
    (pin "AC5")
    (pin "AC6")
    (pin "AD1")
    (pin "AD2")
    (pin "AD3")
    (pin "AD4")
    (pin "AD5")
    (pin "AD6")
    (pin "AE1")
    (pin "AE2")
    (pin "AE3")
    (pin "AE5")
    (pin "AE6")
    (pin "AF2")
    (pin "AF3")
    (pin "AF4")
    (pin "AF5")
    (pin "AF6")
    (pin "T7")
    (pin "U1")
    (pin "U2")
    (pin "U3")
    (pin "U4")
    (pin "U5")
    (pin "U6")
    (pin "U7")
    (pin "V1")
    (pin "V2")
    (pin "V3")
    (pin "V4")
    (pin "V6")
    (pin "W1")
    (pin "W3")
    (pin "W4")
    (pin "W5")
    (pin "W6")
    (pin "Y1")
    (pin "Y2")
    (pin "Y3")
    (pin "Y4")
    (pin "Y5")
    (pin "Y6")
    (pin "A3")
    (pin "A4")
    (pin "B1")
    (pin "B2")
    (pin "B5")
    (pin "B6")
    (pin "C3")
    (pin "C4")
    (pin "D1")
    (pin "D2")
    (pin "D5")
    (pin "D6")
    (pin "E3")
    (pin "E4")
    (pin "F1")
    (pin "F2")
    (pin "F5")
    (pin "F6")
    (pin "G3")
    (pin "G4")
    (pin "H1")
    (pin "H2")
    (pin "H5")
    (pin "H6")
    (pin "J3")
    (pin "J4")
    (pin "K1")
    (pin "K2")
    (pin "K5")
    (pin "K6")
    (pin "L3")
    (pin "L4")
    (pin "M1")
    (pin "M2")
    (pin "N3")
    (pin "N4")
    (pin "P1")
    (pin "P2")
    (pin "R3")
    (pin "R4")
    (pin "A1")
    (pin "A16")
    (pin "A2")
    (pin "A26")
    (pin "A5")
    (pin "A6")
    (pin "A7")
    (pin "AA16")
    (pin "AA26")
    (pin "AA6")
    (pin "AB13")
    (pin "AB23")
    (pin "AB3")
    (pin "AC10")
    (pin "AC20")
    (pin "AD17")
    (pin "AD7")
    (pin "AE14")
    (pin "AE24")
    (pin "AE4")
    (pin "AF1")
    (pin "AF11")
    (pin "AF21")
    (pin "B13")
    (pin "B23")
    (pin "B3")
    (pin "B4")
    (pin "B7")
    (pin "C1")
    (pin "C10")
    (pin "C2")
    (pin "C20")
    (pin "C5")
    (pin "C6")
    (pin "C7")
    (pin "D17")
    (pin "D3")
    (pin "D4")
    (pin "D7")
    (pin "E1")
    (pin "E14")
    (pin "E2")
    (pin "E24")
    (pin "E5")
    (pin "E6")
    (pin "E7")
    (pin "E8")
    (pin "F11")
    (pin "F21")
    (pin "F3")
    (pin "F4")
    (pin "F7")
    (pin "G1")
    (pin "G18")
    (pin "G2")
    (pin "G5")
    (pin "G6")
    (pin "G8")
    (pin "H15")
    (pin "H25")
    (pin "H3")
    (pin "H4")
    (pin "H7")
    (pin "J1")
    (pin "J12")
    (pin "J2")
    (pin "J22")
    (pin "J5")
    (pin "J6")
    (pin "J9")
    (pin "K10")
    (pin "K11")
    (pin "K12")
    (pin "K13")
    (pin "K14")
    (pin "K19")
    (pin "K3")
    (pin "K4")
    (pin "K7")
    (pin "K8")
    (pin "K9")
    (pin "L1")
    (pin "L10")
    (pin "L11")
    (pin "L12")
    (pin "L13")
    (pin "L14")
    (pin "L15")
    (pin "L16")
    (pin "L2")
    (pin "L26")
    (pin "L5")
    (pin "L6")
    (pin "L9")
    (pin "M10")
    (pin "M11")
    (pin "M12")
    (pin "M13")
    (pin "M14")
    (pin "M15")
    (pin "M23")
    (pin "M3")
    (pin "M4")
    (pin "M5")
    (pin "M6")
    (pin "M7")
    (pin "M8")
    (pin "M9")
    (pin "N1")
    (pin "N10")
    (pin "N13")
    (pin "N14")
    (pin "N15")
    (pin "N2")
    (pin "N20")
    (pin "N5")
    (pin "N6")
    (pin "N7")
    (pin "N9")
    (pin "P10")
    (pin "P13")
    (pin "P14")
    (pin "P15")
    (pin "P17")
    (pin "P3")
    (pin "P4")
    (pin "P8")
    (pin "P9")
    (pin "R1")
    (pin "R10")
    (pin "R13")
    (pin "R14")
    (pin "R15")
    (pin "R2")
    (pin "R24")
    (pin "R5")
    (pin "R8")
    (pin "R9")
    (pin "T1")
    (pin "T10")
    (pin "T11")
    (pin "T12")
    (pin "T13")
    (pin "T14")
    (pin "T15")
    (pin "T21")
    (pin "T3")
    (pin "T4")
    (pin "T8")
    (pin "T9")
    (pin "U10")
    (pin "U11")
    (pin "U12")
    (pin "U13")
    (pin "U14")
    (pin "U15")
    (pin "U18")
    (pin "U8")
    (pin "V15")
    (pin "V25")
    (pin "V5")
    (pin "W12")
    (pin "W2")
    (pin "W22")
    (pin "Y19")
    (pin "Y9")
    (pin "C8")
    (pin "G7")
    (pin "J7")
    (pin "L7")
    (pin "L8")
    (pin "N11")
    (pin "N12")
    (pin "N8")
    (pin "P11")
    (pin "P12")
    (pin "P5")
    (pin "P6")
    (pin "P7")
    (pin "R11")
    (pin "R12")
    (pin "R6")
    (pin "R7")
    (pin "T2")
    (pin "T5")
    (pin "T6")
    (instances
      (project "data-center-rdimm-ddr4-tester"
        (path ""
          (reference "U15") (unit 10)
        )
      )
    )
  )

  (symbol (lib_id "antmicropower:GND") (at 266.065 90.17 0) (mirror y) (unit 1)
    (in_bom yes) (on_board yes) (dnp no)
    (property "Reference" "#PWR0112" (at 266.065 96.52 0)
      (effects (font (size 1.27 1.27)) hide)
    )
    (property "Value" "GND" (at 266.065 93.98 0)
      (effects (font (size 1.27 1.27)))
    )
    (property "Footprint" "" (at 266.065 90.17 0)
      (effects (font (size 1.27 1.27)) hide)
    )
    (property "Datasheet" "" (at 266.065 90.17 0)
      (effects (font (size 1.27 1.27)) hide)
    )
    (property "Author" "Antmicro" (at 257.175 97.79 0)
      (effects (font (size 1.27 1.27) (thickness 0.15)) (justify left bottom) hide)
    )
    (property "License" "Apache-2.0" (at 257.175 100.33 0)
      (effects (font (size 1.27 1.27) (thickness 0.15)) (justify left bottom) hide)
    )
    (pin "1")
    (instances
      (project "data-center-rdimm-ddr4-tester"
        (path ""
          (reference "#PWR0112") (unit 1)
        )
      )
    )
  )

  (symbol (lib_id "antmicropower:GND") (at 134.62 36.83 0) (mirror y) (unit 1)
    (in_bom yes) (on_board yes) (dnp no) (fields_autoplaced)
    (property "Reference" "#PWR0101" (at 134.62 43.18 0)
      (effects (font (size 1.27 1.27)) hide)
    )
    (property "Value" "GND" (at 134.62 41.275 0)
      (effects (font (size 1.27 1.27)))
    )
    (property "Footprint" "" (at 134.62 36.83 0)
      (effects (font (size 1.27 1.27)) hide)
    )
    (property "Datasheet" "" (at 134.62 36.83 0)
      (effects (font (size 1.27 1.27)) hide)
    )
    (property "Author" "Antmicro" (at 125.73 44.45 0)
      (effects (font (size 1.27 1.27) (thickness 0.15)) (justify left bottom) hide)
    )
    (property "License" "Apache-2.0" (at 125.73 46.99 0)
      (effects (font (size 1.27 1.27) (thickness 0.15)) (justify left bottom) hide)
    )
    (pin "1")
    (instances
      (project "data-center-rdimm-ddr4-tester"
        (path ""
          (reference "#PWR0101") (unit 1)
        )
      )
    )
  )

  (symbol (lib_id "data-center-rdimm-ddr4-tester:C_330u_KEMET_D") (at 134.62 31.75 0) (unit 1)
    (in_bom yes) (on_board yes) (dnp no)
    (property "Reference" "C8" (at 135.255 32.385 0)
      (effects (font (size 1.524 1.524)) (justify left))
    )
    (property "Value" "C_330u_KEMET_D" (at 148.59 36.83 0)
      (effects (font (size 1.27 1.27) (thickness 0.15)) (justify left bottom) hide)
    )
    (property "Footprint" "data-center-rdimm-ddr4-tester-footprints:KEMET_D" (at 148.59 39.37 0)
      (effects (font (size 1.27 1.27) (thickness 0.15)) (justify left bottom) hide)
    )
    (property "Datasheet" " " (at 148.59 41.91 0)
      (effects (font (size 1.27 1.27) (thickness 0.15)) (justify left bottom) hide)
    )
    (property "Manufacturer" "KEMET" (at 148.59 46.99 0)
      (effects (font (size 1.27 1.27) (thickness 0.15)) (justify left bottom) hide)
    )
    (property "MPN" "T520D337M006ATE045" (at 148.59 44.45 0)
      (effects (font (size 1.27 1.27) (thickness 0.15)) (justify left bottom) hide)
    )
    (property "Val" "330u" (at 135.255 36.195 0)
      (effects (font (size 1.27 1.27) (thickness 0.15)) (justify left))
    )
    (property "License" "Apache-2.0" (at 148.59 49.53 0)
      (effects (font (size 1.27 1.27) (thickness 0.15)) (justify left bottom) hide)
    )
    (property "Author" "Antmicro" (at 148.59 52.07 0)
      (effects (font (size 1.27 1.27) (thickness 0.15)) (justify left bottom) hide)
    )
    (property "Voltage" "" (at 148.59 54.61 0)
      (effects (font (size 1.27 1.27)) (justify left bottom) hide)
    )
    (property "Dielectric" "" (at 148.59 57.15 0)
      (effects (font (size 1.27 1.27)) (justify left bottom) hide)
    )
    (pin "1")
    (pin "2")
    (instances
      (project "data-center-rdimm-ddr4-tester"
        (path ""
          (reference "C8") (unit 1)
        )
      )
    )
  )

  (symbol (lib_id "antmicropower:GND") (at 142.875 36.83 0) (mirror y) (unit 1)
    (in_bom yes) (on_board yes) (dnp no) (fields_autoplaced)
    (property "Reference" "#PWR0102" (at 142.875 43.18 0)
      (effects (font (size 1.27 1.27)) hide)
    )
    (property "Value" "GND" (at 142.875 41.275 0)
      (effects (font (size 1.27 1.27)))
    )
    (property "Footprint" "" (at 142.875 36.83 0)
      (effects (font (size 1.27 1.27)) hide)
    )
    (property "Datasheet" "" (at 142.875 36.83 0)
      (effects (font (size 1.27 1.27)) hide)
    )
    (property "Author" "Antmicro" (at 133.985 44.45 0)
      (effects (font (size 1.27 1.27) (thickness 0.15)) (justify left bottom) hide)
    )
    (property "License" "Apache-2.0" (at 133.985 46.99 0)
      (effects (font (size 1.27 1.27) (thickness 0.15)) (justify left bottom) hide)
    )
    (pin "1")
    (instances
      (project "data-center-rdimm-ddr4-tester"
        (path ""
          (reference "#PWR0102") (unit 1)
        )
      )
    )
  )

  (symbol (lib_id "antmicroCapacitors0402:C_4u7_0402") (at 142.875 31.75 270) (unit 1)
    (in_bom yes) (on_board yes) (dnp no)
    (property "Reference" "C144" (at 143.51 32.385 90)
      (effects (font (size 1.524 1.524)) (justify left))
    )
    (property "Value" "C_4u7_0402" (at 132.715 52.07 0)
      (effects (font (size 1.27 1.27) (thickness 0.15)) (justify left bottom) hide)
    )
    (property "Footprint" "antmicro-footprints:C_0402_1005Metric" (at 130.175 52.07 0)
      (effects (font (size 1.27 1.27) (thickness 0.15)) (justify left bottom) hide)
    )
    (property "Datasheet" " " (at 127.635 52.07 0)
      (effects (font (size 1.27 1.27) (thickness 0.15)) (justify left bottom) hide)
    )
    (property "Manufacturer" "Murata" (at 122.555 52.07 0)
      (effects (font (size 1.27 1.27) (thickness 0.15)) (justify left bottom) hide)
    )
    (property "MPN" "GRM155R61A475MEAAD" (at 125.095 52.07 0)
      (effects (font (size 1.27 1.27) (thickness 0.15)) (justify left bottom) hide)
    )
    (property "Val" "4u7" (at 143.51 36.195 90)
      (effects (font (size 1.27 1.27) (thickness 0.15)) (justify left))
    )
    (property "License" "Apache-2.0" (at 120.015 52.07 0)
      (effects (font (size 1.27 1.27) (thickness 0.15)) (justify left bottom) hide)
    )
    (property "Author" "Antmicro" (at 117.475 52.07 0)
      (effects (font (size 1.27 1.27) (thickness 0.15)) (justify left bottom) hide)
    )
    (property "Voltage" "" (at 114.935 52.07 0)
      (effects (font (size 1.27 1.27)) (justify left bottom) hide)
    )
    (property "Dielectric" "" (at 112.395 52.07 0)
      (effects (font (size 1.27 1.27)) (justify left bottom) hide)
    )
    (pin "1")
    (pin "2")
    (instances
      (project "data-center-rdimm-ddr4-tester"
        (path ""
          (reference "C144") (unit 1)
        )
      )
    )
  )

  (symbol (lib_id "antmicroCapacitors0603:C_47u_0603") (at 143.51 104.775 270) (unit 1)
    (in_bom yes) (on_board yes) (dnp no)
    (property "Reference" "C114" (at 144.145 105.41 90)
      (effects (font (size 1.524 1.524)) (justify left))
    )
    (property "Value" "C_47u_0603" (at 133.35 125.095 0)
      (effects (font (size 1.27 1.27) (thickness 0.15)) (justify left bottom) hide)
    )
    (property "Footprint" "antmicro-footprints:C_0603_1608Metric" (at 130.81 125.095 0)
      (effects (font (size 1.27 1.27) (thickness 0.15)) (justify left bottom) hide)
    )
    (property "Datasheet" " " (at 128.27 125.095 0)
      (effects (font (size 1.27 1.27) (thickness 0.15)) (justify left bottom) hide)
    )
    (property "Manufacturer" "Murata" (at 123.19 125.095 0)
      (effects (font (size 1.27 1.27) (thickness 0.15)) (justify left bottom) hide)
    )
    (property "MPN" "GRM188R60J476ME15D" (at 125.73 125.095 0)
      (effects (font (size 1.27 1.27) (thickness 0.15)) (justify left bottom) hide)
    )
    (property "Val" "47u" (at 144.145 109.22 90)
      (effects (font (size 1.27 1.27) (thickness 0.15)) (justify left))
    )
    (property "License" "Apache-2.0" (at 120.65 125.095 0)
      (effects (font (size 1.27 1.27) (thickness 0.15)) (justify left bottom) hide)
    )
    (property "Author" "Antmicro" (at 118.11 125.095 0)
      (effects (font (size 1.27 1.27) (thickness 0.15)) (justify left bottom) hide)
    )
    (property "Voltage" "" (at 115.57 125.095 0)
      (effects (font (size 1.27 1.27)) (justify left bottom) hide)
    )
    (property "Dielectric" "" (at 113.03 125.095 0)
      (effects (font (size 1.27 1.27)) (justify left bottom) hide)
    )
    (pin "1")
    (pin "2")
    (instances
      (project "data-center-rdimm-ddr4-tester"
        (path ""
          (reference "C114") (unit 1)
        )
      )
    )
  )

  (symbol (lib_id "antmicropower:GND") (at 143.51 109.855 0) (mirror y) (unit 1)
    (in_bom yes) (on_board yes) (dnp no) (fields_autoplaced)
    (property "Reference" "#PWR0103" (at 143.51 116.205 0)
      (effects (font (size 1.27 1.27)) hide)
    )
    (property "Value" "GND" (at 143.51 114.3 0)
      (effects (font (size 1.27 1.27)))
    )
    (property "Footprint" "" (at 143.51 109.855 0)
      (effects (font (size 1.27 1.27)) hide)
    )
    (property "Datasheet" "" (at 143.51 109.855 0)
      (effects (font (size 1.27 1.27)) hide)
    )
    (property "Author" "Antmicro" (at 134.62 117.475 0)
      (effects (font (size 1.27 1.27) (thickness 0.15)) (justify left bottom) hide)
    )
    (property "License" "Apache-2.0" (at 134.62 120.015 0)
      (effects (font (size 1.27 1.27) (thickness 0.15)) (justify left bottom) hide)
    )
    (pin "1")
    (instances
      (project "data-center-rdimm-ddr4-tester"
        (path ""
          (reference "#PWR0103") (unit 1)
        )
      )
    )
  )

  (symbol (lib_id "antmicroCapacitors0402:C_4u7_0402") (at 151.765 104.775 270) (unit 1)
    (in_bom yes) (on_board yes) (dnp no)
    (property "Reference" "C115" (at 152.4 105.41 90)
      (effects (font (size 1.524 1.524)) (justify left))
    )
    (property "Value" "C_4u7_0402" (at 141.605 125.095 0)
      (effects (font (size 1.27 1.27) (thickness 0.15)) (justify left bottom) hide)
    )
    (property "Footprint" "antmicro-footprints:C_0402_1005Metric" (at 139.065 125.095 0)
      (effects (font (size 1.27 1.27) (thickness 0.15)) (justify left bottom) hide)
    )
    (property "Datasheet" " " (at 136.525 125.095 0)
      (effects (font (size 1.27 1.27) (thickness 0.15)) (justify left bottom) hide)
    )
    (property "Manufacturer" "Murata" (at 131.445 125.095 0)
      (effects (font (size 1.27 1.27) (thickness 0.15)) (justify left bottom) hide)
    )
    (property "MPN" "GRM155R61A475MEAAD" (at 133.985 125.095 0)
      (effects (font (size 1.27 1.27) (thickness 0.15)) (justify left bottom) hide)
    )
    (property "Val" "4u7" (at 152.4 109.22 90)
      (effects (font (size 1.27 1.27) (thickness 0.15)) (justify left))
    )
    (property "License" "Apache-2.0" (at 128.905 125.095 0)
      (effects (font (size 1.27 1.27) (thickness 0.15)) (justify left bottom) hide)
    )
    (property "Author" "Antmicro" (at 126.365 125.095 0)
      (effects (font (size 1.27 1.27) (thickness 0.15)) (justify left bottom) hide)
    )
    (property "Voltage" "" (at 123.825 125.095 0)
      (effects (font (size 1.27 1.27)) (justify left bottom) hide)
    )
    (property "Dielectric" "" (at 121.285 125.095 0)
      (effects (font (size 1.27 1.27)) (justify left bottom) hide)
    )
    (pin "1")
    (pin "2")
    (instances
      (project "data-center-rdimm-ddr4-tester"
        (path ""
          (reference "C115") (unit 1)
        )
      )
    )
  )

  (symbol (lib_id "antmicropower:GND") (at 151.765 109.855 0) (mirror y) (unit 1)
    (in_bom yes) (on_board yes) (dnp no) (fields_autoplaced)
    (property "Reference" "#PWR0108" (at 151.765 116.205 0)
      (effects (font (size 1.27 1.27)) hide)
    )
    (property "Value" "GND" (at 151.765 114.3 0)
      (effects (font (size 1.27 1.27)))
    )
    (property "Footprint" "" (at 151.765 109.855 0)
      (effects (font (size 1.27 1.27)) hide)
    )
    (property "Datasheet" "" (at 151.765 109.855 0)
      (effects (font (size 1.27 1.27)) hide)
    )
    (property "Author" "Antmicro" (at 142.875 117.475 0)
      (effects (font (size 1.27 1.27) (thickness 0.15)) (justify left bottom) hide)
    )
    (property "License" "Apache-2.0" (at 142.875 120.015 0)
      (effects (font (size 1.27 1.27) (thickness 0.15)) (justify left bottom) hide)
    )
    (pin "1")
    (instances
      (project "data-center-rdimm-ddr4-tester"
        (path ""
          (reference "#PWR0108") (unit 1)
        )
      )
    )
  )

  (symbol (lib_id "antmicroCapacitors0603:C_47u_0603") (at 52.07 104.775 270) (unit 1)
    (in_bom yes) (on_board yes) (dnp no)
    (property "Reference" "C22" (at 52.07 105.41 90)
      (effects (font (size 1.524 1.524)) (justify left))
    )
    (property "Value" "C_47u_0603" (at 41.91 125.095 0)
      (effects (font (size 1.27 1.27) (thickness 0.15)) (justify left bottom) hide)
    )
    (property "Footprint" "antmicro-footprints:C_0603_1608Metric" (at 39.37 125.095 0)
      (effects (font (size 1.27 1.27) (thickness 0.15)) (justify left bottom) hide)
    )
    (property "Datasheet" " " (at 36.83 125.095 0)
      (effects (font (size 1.27 1.27) (thickness 0.15)) (justify left bottom) hide)
    )
    (property "Manufacturer" "Murata" (at 31.75 125.095 0)
      (effects (font (size 1.27 1.27) (thickness 0.15)) (justify left bottom) hide)
    )
    (property "MPN" "GRM188R60J476ME15D" (at 34.29 125.095 0)
      (effects (font (size 1.27 1.27) (thickness 0.15)) (justify left bottom) hide)
    )
    (property "Val" "47u" (at 52.07 109.22 90)
      (effects (font (size 1.27 1.27) (thickness 0.15)) (justify left))
    )
    (property "License" "Apache-2.0" (at 29.21 125.095 0)
      (effects (font (size 1.27 1.27) (thickness 0.15)) (justify left bottom) hide)
    )
    (property "Author" "Antmicro" (at 26.67 125.095 0)
      (effects (font (size 1.27 1.27) (thickness 0.15)) (justify left bottom) hide)
    )
    (property "Voltage" "" (at 24.13 125.095 0)
      (effects (font (size 1.27 1.27)) (justify left bottom) hide)
    )
    (property "Dielectric" "" (at 21.59 125.095 0)
      (effects (font (size 1.27 1.27)) (justify left bottom) hide)
    )
    (pin "1")
    (pin "2")
    (instances
      (project "data-center-rdimm-ddr4-tester"
        (path ""
          (reference "C22") (unit 1)
        )
      )
    )
  )

  (symbol (lib_id "antmicroCapacitors0603:C_47u_0603") (at 59.055 104.775 270) (unit 1)
    (in_bom yes) (on_board yes) (dnp no)
    (property "Reference" "C25" (at 59.055 105.41 90)
      (effects (font (size 1.524 1.524)) (justify left))
    )
    (property "Value" "C_47u_0603" (at 48.895 125.095 0)
      (effects (font (size 1.27 1.27) (thickness 0.15)) (justify left bottom) hide)
    )
    (property "Footprint" "antmicro-footprints:C_0603_1608Metric" (at 46.355 125.095 0)
      (effects (font (size 1.27 1.27) (thickness 0.15)) (justify left bottom) hide)
    )
    (property "Datasheet" " " (at 43.815 125.095 0)
      (effects (font (size 1.27 1.27) (thickness 0.15)) (justify left bottom) hide)
    )
    (property "Manufacturer" "Murata" (at 38.735 125.095 0)
      (effects (font (size 1.27 1.27) (thickness 0.15)) (justify left bottom) hide)
    )
    (property "MPN" "GRM188R60J476ME15D" (at 41.275 125.095 0)
      (effects (font (size 1.27 1.27) (thickness 0.15)) (justify left bottom) hide)
    )
    (property "Val" "47u" (at 59.055 109.22 90)
      (effects (font (size 1.27 1.27) (thickness 0.15)) (justify left))
    )
    (property "License" "Apache-2.0" (at 36.195 125.095 0)
      (effects (font (size 1.27 1.27) (thickness 0.15)) (justify left bottom) hide)
    )
    (property "Author" "Antmicro" (at 33.655 125.095 0)
      (effects (font (size 1.27 1.27) (thickness 0.15)) (justify left bottom) hide)
    )
    (property "Voltage" "" (at 31.115 125.095 0)
      (effects (font (size 1.27 1.27)) (justify left bottom) hide)
    )
    (property "Dielectric" "" (at 28.575 125.095 0)
      (effects (font (size 1.27 1.27)) (justify left bottom) hide)
    )
    (pin "1")
    (pin "2")
    (instances
      (project "data-center-rdimm-ddr4-tester"
        (path ""
          (reference "C25") (unit 1)
        )
      )
    )
  )

  (symbol (lib_id "antmicroCapacitors0402:C_4u7_0402") (at 45.085 104.775 270) (unit 1)
    (in_bom yes) (on_board yes) (dnp no)
    (property "Reference" "C19" (at 45.085 105.41 90)
      (effects (font (size 1.524 1.524)) (justify left))
    )
    (property "Value" "C_4u7_0402" (at 34.925 125.095 0)
      (effects (font (size 1.27 1.27) (thickness 0.15)) (justify left bottom) hide)
    )
    (property "Footprint" "antmicro-footprints:C_0402_1005Metric" (at 32.385 125.095 0)
      (effects (font (size 1.27 1.27) (thickness 0.15)) (justify left bottom) hide)
    )
    (property "Datasheet" " " (at 29.845 125.095 0)
      (effects (font (size 1.27 1.27) (thickness 0.15)) (justify left bottom) hide)
    )
    (property "Manufacturer" "Murata" (at 24.765 125.095 0)
      (effects (font (size 1.27 1.27) (thickness 0.15)) (justify left bottom) hide)
    )
    (property "MPN" "GRM155R61A475MEAAD" (at 27.305 125.095 0)
      (effects (font (size 1.27 1.27) (thickness 0.15)) (justify left bottom) hide)
    )
    (property "Val" "4u7" (at 45.085 109.22 90)
      (effects (font (size 1.27 1.27) (thickness 0.15)) (justify left))
    )
    (property "License" "Apache-2.0" (at 22.225 125.095 0)
      (effects (font (size 1.27 1.27) (thickness 0.15)) (justify left bottom) hide)
    )
    (property "Author" "Antmicro" (at 19.685 125.095 0)
      (effects (font (size 1.27 1.27) (thickness 0.15)) (justify left bottom) hide)
    )
    (property "Voltage" "" (at 17.145 125.095 0)
      (effects (font (size 1.27 1.27)) (justify left bottom) hide)
    )
    (property "Dielectric" "" (at 14.605 125.095 0)
      (effects (font (size 1.27 1.27)) (justify left bottom) hide)
    )
    (pin "1")
    (pin "2")
    (instances
      (project "data-center-rdimm-ddr4-tester"
        (path ""
          (reference "C19") (unit 1)
        )
      )
    )
  )

  (symbol (lib_id "antmicroCapacitors0402:C_4u7_0402") (at 38.1 104.775 270) (unit 1)
    (in_bom yes) (on_board yes) (dnp no)
    (property "Reference" "C16" (at 38.1 105.41 90)
      (effects (font (size 1.524 1.524)) (justify left))
    )
    (property "Value" "C_4u7_0402" (at 27.94 125.095 0)
      (effects (font (size 1.27 1.27) (thickness 0.15)) (justify left bottom) hide)
    )
    (property "Footprint" "antmicro-footprints:C_0402_1005Metric" (at 25.4 125.095 0)
      (effects (font (size 1.27 1.27) (thickness 0.15)) (justify left bottom) hide)
    )
    (property "Datasheet" " " (at 22.86 125.095 0)
      (effects (font (size 1.27 1.27) (thickness 0.15)) (justify left bottom) hide)
    )
    (property "Manufacturer" "Murata" (at 17.78 125.095 0)
      (effects (font (size 1.27 1.27) (thickness 0.15)) (justify left bottom) hide)
    )
    (property "MPN" "GRM155R61A475MEAAD" (at 20.32 125.095 0)
      (effects (font (size 1.27 1.27) (thickness 0.15)) (justify left bottom) hide)
    )
    (property "Val" "4u7" (at 38.1 109.22 90)
      (effects (font (size 1.27 1.27) (thickness 0.15)) (justify left))
    )
    (property "License" "Apache-2.0" (at 15.24 125.095 0)
      (effects (font (size 1.27 1.27) (thickness 0.15)) (justify left bottom) hide)
    )
    (property "Author" "Antmicro" (at 12.7 125.095 0)
      (effects (font (size 1.27 1.27) (thickness 0.15)) (justify left bottom) hide)
    )
    (property "Voltage" "" (at 10.16 125.095 0)
      (effects (font (size 1.27 1.27)) (justify left bottom) hide)
    )
    (property "Dielectric" "" (at 7.62 125.095 0)
      (effects (font (size 1.27 1.27)) (justify left bottom) hide)
    )
    (pin "1")
    (pin "2")
    (instances
      (project "data-center-rdimm-ddr4-tester"
        (path ""
          (reference "C16") (unit 1)
        )
      )
    )
  )

  (symbol (lib_id "antmicroCapacitors0402:C_4u7_0402") (at 31.115 104.775 270) (unit 1)
    (in_bom yes) (on_board yes) (dnp no)
    (property "Reference" "C7" (at 31.115 105.41 90)
      (effects (font (size 1.524 1.524)) (justify left))
    )
    (property "Value" "C_4u7_0402" (at 20.955 125.095 0)
      (effects (font (size 1.27 1.27) (thickness 0.15)) (justify left bottom) hide)
    )
    (property "Footprint" "antmicro-footprints:C_0402_1005Metric" (at 18.415 125.095 0)
      (effects (font (size 1.27 1.27) (thickness 0.15)) (justify left bottom) hide)
    )
    (property "Datasheet" " " (at 15.875 125.095 0)
      (effects (font (size 1.27 1.27) (thickness 0.15)) (justify left bottom) hide)
    )
    (property "Manufacturer" "Murata" (at 10.795 125.095 0)
      (effects (font (size 1.27 1.27) (thickness 0.15)) (justify left bottom) hide)
    )
    (property "MPN" "GRM155R61A475MEAAD" (at 13.335 125.095 0)
      (effects (font (size 1.27 1.27) (thickness 0.15)) (justify left bottom) hide)
    )
    (property "Val" "4u7" (at 31.115 109.22 90)
      (effects (font (size 1.27 1.27) (thickness 0.15)) (justify left))
    )
    (property "License" "Apache-2.0" (at 8.255 125.095 0)
      (effects (font (size 1.27 1.27) (thickness 0.15)) (justify left bottom) hide)
    )
    (property "Author" "Antmicro" (at 5.715 125.095 0)
      (effects (font (size 1.27 1.27) (thickness 0.15)) (justify left bottom) hide)
    )
    (property "Voltage" "" (at 3.175 125.095 0)
      (effects (font (size 1.27 1.27)) (justify left bottom) hide)
    )
    (property "Dielectric" "" (at 0.635 125.095 0)
      (effects (font (size 1.27 1.27)) (justify left bottom) hide)
    )
    (pin "1")
    (pin "2")
    (instances
      (project "data-center-rdimm-ddr4-tester"
        (path ""
          (reference "C7") (unit 1)
        )
      )
    )
  )

  (symbol (lib_id "data-center-rdimm-ddr4-tester:C_100u_KEMET_A") (at 156.21 66.04 0) (unit 1)
    (in_bom yes) (on_board yes) (dnp no)
    (property "Reference" "C20" (at 156.21 66.675 0)
      (effects (font (size 1.524 1.524)) (justify left))
    )
    (property "Value" "C_100u_KEMET_A" (at 170.18 71.12 0)
      (effects (font (size 1.27 1.27) (thickness 0.15)) (justify left bottom) hide)
    )
    (property "Footprint" "data-center-rdimm-ddr4-tester-footprints:KEMET_A" (at 170.18 73.66 0)
      (effects (font (size 1.27 1.27) (thickness 0.15)) (justify left bottom) hide)
    )
    (property "Datasheet" " " (at 170.18 76.2 0)
      (effects (font (size 1.27 1.27) (thickness 0.15)) (justify left bottom) hide)
    )
    (property "Manufacturer" "Vishay" (at 170.18 81.28 0)
      (effects (font (size 1.27 1.27) (thickness 0.15)) (justify left bottom) hide)
    )
    (property "MPN" "298D107X06R3A2T" (at 170.18 78.74 0)
      (effects (font (size 1.27 1.27) (thickness 0.15)) (justify left bottom) hide)
    )
    (property "Val" "100u" (at 156.21 70.485 0)
      (effects (font (size 1.27 1.27) (thickness 0.15)) (justify left))
    )
    (property "License" "Apache-2.0" (at 170.18 83.82 0)
      (effects (font (size 1.27 1.27) (thickness 0.15)) (justify left bottom) hide)
    )
    (property "Author" "Antmicro" (at 170.18 86.36 0)
      (effects (font (size 1.27 1.27) (thickness 0.15)) (justify left bottom) hide)
    )
    (property "Voltage" "" (at 170.18 88.9 0)
      (effects (font (size 1.27 1.27)) (justify left bottom) hide)
    )
    (property "Dielectric" "" (at 170.18 91.44 0)
      (effects (font (size 1.27 1.27)) (justify left bottom) hide)
    )
    (pin "1")
    (pin "2")
    (instances
      (project "data-center-rdimm-ddr4-tester"
        (path ""
          (reference "C20") (unit 1)
        )
      )
    )
  )

  (symbol (lib_id "antmicroCapacitors0402:C_4u7_0402") (at 149.225 66.04 270) (unit 1)
    (in_bom yes) (on_board yes) (dnp no)
    (property "Reference" "C17" (at 149.225 66.675 90)
      (effects (font (size 1.524 1.524)) (justify left))
    )
    (property "Value" "C_4u7_0402" (at 139.065 86.36 0)
      (effects (font (size 1.27 1.27) (thickness 0.15)) (justify left bottom) hide)
    )
    (property "Footprint" "antmicro-footprints:C_0402_1005Metric" (at 136.525 86.36 0)
      (effects (font (size 1.27 1.27) (thickness 0.15)) (justify left bottom) hide)
    )
    (property "Datasheet" " " (at 133.985 86.36 0)
      (effects (font (size 1.27 1.27) (thickness 0.15)) (justify left bottom) hide)
    )
    (property "Manufacturer" "Murata" (at 128.905 86.36 0)
      (effects (font (size 1.27 1.27) (thickness 0.15)) (justify left bottom) hide)
    )
    (property "MPN" "GRM155R61A475MEAAD" (at 131.445 86.36 0)
      (effects (font (size 1.27 1.27) (thickness 0.15)) (justify left bottom) hide)
    )
    (property "Val" "4u7" (at 149.225 70.485 90)
      (effects (font (size 1.27 1.27) (thickness 0.15)) (justify left))
    )
    (property "License" "Apache-2.0" (at 126.365 86.36 0)
      (effects (font (size 1.27 1.27) (thickness 0.15)) (justify left bottom) hide)
    )
    (property "Author" "Antmicro" (at 123.825 86.36 0)
      (effects (font (size 1.27 1.27) (thickness 0.15)) (justify left bottom) hide)
    )
    (property "Voltage" "" (at 121.285 86.36 0)
      (effects (font (size 1.27 1.27)) (justify left bottom) hide)
    )
    (property "Dielectric" "" (at 118.745 86.36 0)
      (effects (font (size 1.27 1.27)) (justify left bottom) hide)
    )
    (pin "1")
    (pin "2")
    (instances
      (project "data-center-rdimm-ddr4-tester"
        (path ""
          (reference "C17") (unit 1)
        )
      )
    )
  )

  (symbol (lib_id "antmicroCapacitors0402:C_4u7_0402") (at 142.24 66.04 270) (unit 1)
    (in_bom yes) (on_board yes) (dnp no)
    (property "Reference" "C14" (at 142.24 66.675 90)
      (effects (font (size 1.524 1.524)) (justify left))
    )
    (property "Value" "C_4u7_0402" (at 132.08 86.36 0)
      (effects (font (size 1.27 1.27) (thickness 0.15)) (justify left bottom) hide)
    )
    (property "Footprint" "antmicro-footprints:C_0402_1005Metric" (at 129.54 86.36 0)
      (effects (font (size 1.27 1.27) (thickness 0.15)) (justify left bottom) hide)
    )
    (property "Datasheet" " " (at 127 86.36 0)
      (effects (font (size 1.27 1.27) (thickness 0.15)) (justify left bottom) hide)
    )
    (property "Manufacturer" "Murata" (at 121.92 86.36 0)
      (effects (font (size 1.27 1.27) (thickness 0.15)) (justify left bottom) hide)
    )
    (property "MPN" "GRM155R61A475MEAAD" (at 124.46 86.36 0)
      (effects (font (size 1.27 1.27) (thickness 0.15)) (justify left bottom) hide)
    )
    (property "Val" "4u7" (at 142.24 70.485 90)
      (effects (font (size 1.27 1.27) (thickness 0.15)) (justify left))
    )
    (property "License" "Apache-2.0" (at 119.38 86.36 0)
      (effects (font (size 1.27 1.27) (thickness 0.15)) (justify left bottom) hide)
    )
    (property "Author" "Antmicro" (at 116.84 86.36 0)
      (effects (font (size 1.27 1.27) (thickness 0.15)) (justify left bottom) hide)
    )
    (property "Voltage" "" (at 114.3 86.36 0)
      (effects (font (size 1.27 1.27)) (justify left bottom) hide)
    )
    (property "Dielectric" "" (at 111.76 86.36 0)
      (effects (font (size 1.27 1.27)) (justify left bottom) hide)
    )
    (pin "1")
    (pin "2")
    (instances
      (project "data-center-rdimm-ddr4-tester"
        (path ""
          (reference "C14") (unit 1)
        )
      )
    )
  )

  (symbol (lib_id "data-center-rdimm-ddr4-tester:C_330u_KEMET_D") (at 135.255 66.04 0) (unit 1)
    (in_bom yes) (on_board yes) (dnp no)
    (property "Reference" "C26" (at 135.255 66.675 0)
      (effects (font (size 1.524 1.524)) (justify left))
    )
    (property "Value" "C_330u_KEMET_D" (at 149.225 71.12 0)
      (effects (font (size 1.27 1.27) (thickness 0.15)) (justify left bottom) hide)
    )
    (property "Footprint" "data-center-rdimm-ddr4-tester-footprints:KEMET_D" (at 149.225 73.66 0)
      (effects (font (size 1.27 1.27) (thickness 0.15)) (justify left bottom) hide)
    )
    (property "Datasheet" " " (at 149.225 76.2 0)
      (effects (font (size 1.27 1.27) (thickness 0.15)) (justify left bottom) hide)
    )
    (property "Manufacturer" "KEMET" (at 149.225 81.28 0)
      (effects (font (size 1.27 1.27) (thickness 0.15)) (justify left bottom) hide)
    )
    (property "MPN" "T520D337M006ATE045" (at 149.225 78.74 0)
      (effects (font (size 1.27 1.27) (thickness 0.15)) (justify left bottom) hide)
    )
    (property "Val" "330u" (at 135.255 70.485 0)
      (effects (font (size 1.27 1.27) (thickness 0.15)) (justify left))
    )
    (property "License" "Apache-2.0" (at 149.225 83.82 0)
      (effects (font (size 1.27 1.27) (thickness 0.15)) (justify left bottom) hide)
    )
    (property "Author" "Antmicro" (at 149.225 86.36 0)
      (effects (font (size 1.27 1.27) (thickness 0.15)) (justify left bottom) hide)
    )
    (property "Voltage" "" (at 149.225 88.9 0)
      (effects (font (size 1.27 1.27)) (justify left bottom) hide)
    )
    (property "Dielectric" "" (at 149.225 91.44 0)
      (effects (font (size 1.27 1.27)) (justify left bottom) hide)
    )
    (pin "1")
    (pin "2")
    (instances
      (project "data-center-rdimm-ddr4-tester"
        (path ""
          (reference "C26") (unit 1)
        )
      )
    )
  )

  (symbol (lib_id "antmicropower:GND") (at 135.255 71.12 0) (mirror y) (unit 1)
    (in_bom yes) (on_board yes) (dnp no) (fields_autoplaced)
    (property "Reference" "#PWR0124" (at 135.255 77.47 0)
      (effects (font (size 1.27 1.27)) hide)
    )
    (property "Value" "GND" (at 135.255 76.2 0)
      (effects (font (size 1.27 1.27)))
    )
    (property "Footprint" "" (at 135.255 71.12 0)
      (effects (font (size 1.27 1.27)) hide)
    )
    (property "Datasheet" "" (at 135.255 71.12 0)
      (effects (font (size 1.27 1.27)) hide)
    )
    (property "Author" "Antmicro" (at 126.365 78.74 0)
      (effects (font (size 1.27 1.27) (thickness 0.15)) (justify left bottom) hide)
    )
    (property "License" "Apache-2.0" (at 126.365 81.28 0)
      (effects (font (size 1.27 1.27) (thickness 0.15)) (justify left bottom) hide)
    )
    (pin "1")
    (instances
      (project "data-center-rdimm-ddr4-tester"
        (path ""
          (reference "#PWR0124") (unit 1)
        )
      )
    )
  )

  (symbol (lib_id "antmicroCapacitors0603:C_47u_0603") (at 37.465 135.255 270) (unit 1)
    (in_bom yes) (on_board yes) (dnp no)
    (property "Reference" "C81" (at 37.465 135.89 90)
      (effects (font (size 1.524 1.524)) (justify left))
    )
    (property "Value" "C_47u_0603" (at 27.305 155.575 0)
      (effects (font (size 1.27 1.27) (thickness 0.15)) (justify left bottom) hide)
    )
    (property "Footprint" "antmicro-footprints:C_0603_1608Metric" (at 24.765 155.575 0)
      (effects (font (size 1.27 1.27) (thickness 0.15)) (justify left bottom) hide)
    )
    (property "Datasheet" " " (at 22.225 155.575 0)
      (effects (font (size 1.27 1.27) (thickness 0.15)) (justify left bottom) hide)
    )
    (property "Manufacturer" "Murata" (at 17.145 155.575 0)
      (effects (font (size 1.27 1.27) (thickness 0.15)) (justify left bottom) hide)
    )
    (property "MPN" "GRM188R60J476ME15D" (at 19.685 155.575 0)
      (effects (font (size 1.27 1.27) (thickness 0.15)) (justify left bottom) hide)
    )
    (property "Val" "47u" (at 37.465 139.7 90)
      (effects (font (size 1.27 1.27) (thickness 0.15)) (justify left))
    )
    (property "License" "Apache-2.0" (at 14.605 155.575 0)
      (effects (font (size 1.27 1.27) (thickness 0.15)) (justify left bottom) hide)
    )
    (property "Author" "Antmicro" (at 12.065 155.575 0)
      (effects (font (size 1.27 1.27) (thickness 0.15)) (justify left bottom) hide)
    )
    (property "Voltage" "" (at 9.525 155.575 0)
      (effects (font (size 1.27 1.27)) (justify left bottom) hide)
    )
    (property "Dielectric" "" (at 6.985 155.575 0)
      (effects (font (size 1.27 1.27)) (justify left bottom) hide)
    )
    (pin "1")
    (pin "2")
    (instances
      (project "data-center-rdimm-ddr4-tester"
        (path ""
          (reference "C81") (unit 1)
        )
      )
    )
  )

  (symbol (lib_id "antmicroCapacitorsmisc:C_100n_0201") (at 102.87 201.295 270) (unit 1)
    (in_bom yes) (on_board yes) (dnp no)
    (property "Reference" "C93" (at 102.87 201.93 90)
      (effects (font (size 1.524 1.524)) (justify left))
    )
    (property "Value" "C_100n_0201" (at 92.71 221.615 0)
      (effects (font (size 1.27 1.27) (thickness 0.15)) (justify left bottom) hide)
    )
    (property "Footprint" "antmicro-footprints:C_0201" (at 90.17 221.615 0)
      (effects (font (size 1.27 1.27) (thickness 0.15)) (justify left bottom) hide)
    )
    (property "Datasheet" " " (at 87.63 221.615 0)
      (effects (font (size 1.27 1.27) (thickness 0.15)) (justify left bottom) hide)
    )
    (property "Manufacturer" "Yaego" (at 82.55 221.615 0)
      (effects (font (size 1.27 1.27) (thickness 0.15)) (justify left bottom) hide)
    )
    (property "MPN" "CC0201KRX6S5BB104" (at 85.09 221.615 0)
      (effects (font (size 1.27 1.27) (thickness 0.15)) (justify left bottom) hide)
    )
    (property "Val" "100n" (at 102.87 205.74 90)
      (effects (font (size 1.27 1.27) (thickness 0.15)) (justify left))
    )
    (property "License" "Apache-2.0" (at 80.01 221.615 0)
      (effects (font (size 1.27 1.27) (thickness 0.15)) (justify left bottom) hide)
    )
    (property "Author" "Antmicro" (at 77.47 221.615 0)
      (effects (font (size 1.27 1.27) (thickness 0.15)) (justify left bottom) hide)
    )
    (property "Voltage" "" (at 74.93 221.615 0)
      (effects (font (size 1.27 1.27)) (justify left bottom) hide)
    )
    (property "Dielectric" "" (at 72.39 221.615 0)
      (effects (font (size 1.27 1.27)) (justify left bottom) hide)
    )
    (pin "1")
    (pin "2")
    (instances
      (project "data-center-rdimm-ddr4-tester"
        (path ""
          (reference "C93") (unit 1)
        )
      )
    )
  )

  (symbol (lib_id "antmicroCapacitorsmisc:C_100n_0201") (at 76.2 201.295 270) (unit 1)
    (in_bom yes) (on_board yes) (dnp no)
    (property "Reference" "C89" (at 76.2 201.93 90)
      (effects (font (size 1.524 1.524)) (justify left))
    )
    (property "Value" "C_100n_0201" (at 66.04 221.615 0)
      (effects (font (size 1.27 1.27) (thickness 0.15)) (justify left bottom) hide)
    )
    (property "Footprint" "antmicro-footprints:C_0201" (at 63.5 221.615 0)
      (effects (font (size 1.27 1.27) (thickness 0.15)) (justify left bottom) hide)
    )
    (property "Datasheet" " " (at 60.96 221.615 0)
      (effects (font (size 1.27 1.27) (thickness 0.15)) (justify left bottom) hide)
    )
    (property "Manufacturer" "Yaego" (at 55.88 221.615 0)
      (effects (font (size 1.27 1.27) (thickness 0.15)) (justify left bottom) hide)
    )
    (property "MPN" "CC0201KRX6S5BB104" (at 58.42 221.615 0)
      (effects (font (size 1.27 1.27) (thickness 0.15)) (justify left bottom) hide)
    )
    (property "Val" "100n" (at 76.2 205.74 90)
      (effects (font (size 1.27 1.27) (thickness 0.15)) (justify left))
    )
    (property "License" "Apache-2.0" (at 53.34 221.615 0)
      (effects (font (size 1.27 1.27) (thickness 0.15)) (justify left bottom) hide)
    )
    (property "Author" "Antmicro" (at 50.8 221.615 0)
      (effects (font (size 1.27 1.27) (thickness 0.15)) (justify left bottom) hide)
    )
    (property "Voltage" "" (at 48.26 221.615 0)
      (effects (font (size 1.27 1.27)) (justify left bottom) hide)
    )
    (property "Dielectric" "" (at 45.72 221.615 0)
      (effects (font (size 1.27 1.27)) (justify left bottom) hide)
    )
    (pin "1")
    (pin "2")
    (instances
      (project "data-center-rdimm-ddr4-tester"
        (path ""
          (reference "C89") (unit 1)
        )
      )
    )
  )

  (symbol (lib_id "antmicroCapacitorsmisc:C_100n_0201") (at 57.785 170.18 270) (unit 1)
    (in_bom yes) (on_board yes) (dnp no)
    (property "Reference" "C279" (at 57.785 170.815 90)
      (effects (font (size 1.524 1.524)) (justify left))
    )
    (property "Value" "C_100n_0201" (at 47.625 190.5 0)
      (effects (font (size 1.27 1.27) (thickness 0.15)) (justify left bottom) hide)
    )
    (property "Footprint" "antmicro-footprints:C_0201" (at 45.085 190.5 0)
      (effects (font (size 1.27 1.27) (thickness 0.15)) (justify left bottom) hide)
    )
    (property "Datasheet" " " (at 42.545 190.5 0)
      (effects (font (size 1.27 1.27) (thickness 0.15)) (justify left bottom) hide)
    )
    (property "Manufacturer" "Yaego" (at 37.465 190.5 0)
      (effects (font (size 1.27 1.27) (thickness 0.15)) (justify left bottom) hide)
    )
    (property "MPN" "CC0201KRX6S5BB104" (at 40.005 190.5 0)
      (effects (font (size 1.27 1.27) (thickness 0.15)) (justify left bottom) hide)
    )
    (property "Val" "100n" (at 57.785 174.625 90)
      (effects (font (size 1.27 1.27) (thickness 0.15)) (justify left))
    )
    (property "License" "Apache-2.0" (at 34.925 190.5 0)
      (effects (font (size 1.27 1.27) (thickness 0.15)) (justify left bottom) hide)
    )
    (property "Author" "Antmicro" (at 32.385 190.5 0)
      (effects (font (size 1.27 1.27) (thickness 0.15)) (justify left bottom) hide)
    )
    (property "Voltage" "" (at 29.845 190.5 0)
      (effects (font (size 1.27 1.27)) (justify left bottom) hide)
    )
    (property "Dielectric" "" (at 27.305 190.5 0)
      (effects (font (size 1.27 1.27)) (justify left bottom) hide)
    )
    (pin "1")
    (pin "2")
    (instances
      (project "data-center-rdimm-ddr4-tester"
        (path ""
          (reference "C279") (unit 1)
        )
      )
    )
  )

  (symbol (lib_id "antmicroCapacitors0402:C_4u7_0402") (at 292.1 111.125 270) (unit 1)
    (in_bom yes) (on_board yes) (dnp no)
    (property "Reference" "C245" (at 292.735 111.76 90)
      (effects (font (size 1.524 1.524)) (justify left))
    )
    (property "Value" "C_4u7_0402" (at 281.94 131.445 0)
      (effects (font (size 1.27 1.27) (thickness 0.15)) (justify left bottom) hide)
    )
    (property "Footprint" "antmicro-footprints:C_0402_1005Metric" (at 279.4 131.445 0)
      (effects (font (size 1.27 1.27) (thickness 0.15)) (justify left bottom) hide)
    )
    (property "Datasheet" " " (at 276.86 131.445 0)
      (effects (font (size 1.27 1.27) (thickness 0.15)) (justify left bottom) hide)
    )
    (property "Manufacturer" "Murata" (at 271.78 131.445 0)
      (effects (font (size 1.27 1.27) (thickness 0.15)) (justify left bottom) hide)
    )
    (property "MPN" "GRM155R61A475MEAAD" (at 274.32 131.445 0)
      (effects (font (size 1.27 1.27) (thickness 0.15)) (justify left bottom) hide)
    )
    (property "Val" "4u7" (at 292.735 115.57 90)
      (effects (font (size 1.27 1.27) (thickness 0.15)) (justify left))
    )
    (property "License" "Apache-2.0" (at 269.24 131.445 0)
      (effects (font (size 1.27 1.27) (thickness 0.15)) (justify left bottom) hide)
    )
    (property "Author" "Antmicro" (at 266.7 131.445 0)
      (effects (font (size 1.27 1.27) (thickness 0.15)) (justify left bottom) hide)
    )
    (property "Voltage" "" (at 264.16 131.445 0)
      (effects (font (size 1.27 1.27)) (justify left bottom) hide)
    )
    (property "Dielectric" "" (at 261.62 131.445 0)
      (effects (font (size 1.27 1.27)) (justify left bottom) hide)
    )
    (pin "1")
    (pin "2")
    (instances
      (project "data-center-rdimm-ddr4-tester"
        (path ""
          (reference "C245") (unit 1)
        )
      )
    )
  )

  (symbol (lib_id "antmicroCapacitorsmisc:C_100n_0201") (at 371.475 111.125 270) (unit 1)
    (in_bom yes) (on_board yes) (dnp no)
    (property "Reference" "C255" (at 372.11 111.76 90)
      (effects (font (size 1.524 1.524)) (justify left))
    )
    (property "Value" "C_100n_0201" (at 361.315 131.445 0)
      (effects (font (size 1.27 1.27) (thickness 0.15)) (justify left bottom) hide)
    )
    (property "Footprint" "antmicro-footprints:C_0201" (at 358.775 131.445 0)
      (effects (font (size 1.27 1.27) (thickness 0.15)) (justify left bottom) hide)
    )
    (property "Datasheet" " " (at 356.235 131.445 0)
      (effects (font (size 1.27 1.27) (thickness 0.15)) (justify left bottom) hide)
    )
    (property "Manufacturer" "Yaego" (at 351.155 131.445 0)
      (effects (font (size 1.27 1.27) (thickness 0.15)) (justify left bottom) hide)
    )
    (property "MPN" "CC0201KRX6S5BB104" (at 353.695 131.445 0)
      (effects (font (size 1.27 1.27) (thickness 0.15)) (justify left bottom) hide)
    )
    (property "Val" "100n" (at 372.11 115.57 90)
      (effects (font (size 1.27 1.27) (thickness 0.15)) (justify left))
    )
    (property "License" "Apache-2.0" (at 348.615 131.445 0)
      (effects (font (size 1.27 1.27) (thickness 0.15)) (justify left bottom) hide)
    )
    (property "Author" "Antmicro" (at 346.075 131.445 0)
      (effects (font (size 1.27 1.27) (thickness 0.15)) (justify left bottom) hide)
    )
    (property "Voltage" "" (at 343.535 131.445 0)
      (effects (font (size 1.27 1.27)) (justify left bottom) hide)
    )
    (property "Dielectric" "" (at 340.995 131.445 0)
      (effects (font (size 1.27 1.27)) (justify left bottom) hide)
    )
    (pin "1")
    (pin "2")
    (instances
      (project "data-center-rdimm-ddr4-tester"
        (path ""
          (reference "C255") (unit 1)
        )
      )
    )
  )

  (symbol (lib_id "antmicropower:GND") (at 108.585 237.49 0) (unit 1)
    (in_bom yes) (on_board yes) (dnp no) (fields_autoplaced)
    (property "Reference" "#PWR0385" (at 108.585 243.84 0)
      (effects (font (size 1.27 1.27)) hide)
    )
    (property "Value" "GND" (at 108.585 241.935 0)
      (effects (font (size 1.27 1.27)))
    )
    (property "Footprint" "" (at 108.585 237.49 0)
      (effects (font (size 1.27 1.27)) hide)
    )
    (property "Datasheet" "" (at 108.585 237.49 0)
      (effects (font (size 1.27 1.27)) hide)
    )
    (property "Author" "Antmicro" (at 117.475 245.11 0)
      (effects (font (size 1.27 1.27) (thickness 0.15)) (justify left bottom) hide)
    )
    (property "License" "Apache-2.0" (at 117.475 247.65 0)
      (effects (font (size 1.27 1.27) (thickness 0.15)) (justify left bottom) hide)
    )
    (pin "1")
    (instances
      (project "data-center-rdimm-ddr4-tester"
        (path ""
          (reference "#PWR0385") (unit 1)
        )
      )
    )
  )

  (symbol (lib_id "antmicropower:GND") (at 262.89 116.205 0) (unit 1)
    (in_bom yes) (on_board yes) (dnp no) (fields_autoplaced)
    (property "Reference" "#PWR0138" (at 262.89 122.555 0)
      (effects (font (size 1.27 1.27)) hide)
    )
    (property "Value" "GND" (at 262.89 120.65 0)
      (effects (font (size 1.27 1.27)))
    )
    (property "Footprint" "" (at 262.89 116.205 0)
      (effects (font (size 1.27 1.27)) hide)
    )
    (property "Datasheet" "" (at 262.89 116.205 0)
      (effects (font (size 1.27 1.27)) hide)
    )
    (property "Author" "Antmicro" (at 271.78 123.825 0)
      (effects (font (size 1.27 1.27) (thickness 0.15)) (justify left bottom) hide)
    )
    (property "License" "Apache-2.0" (at 271.78 126.365 0)
      (effects (font (size 1.27 1.27) (thickness 0.15)) (justify left bottom) hide)
    )
    (pin "1")
    (instances
      (project "data-center-rdimm-ddr4-tester"
        (path ""
          (reference "#PWR0138") (unit 1)
        )
      )
    )
  )

  (symbol (lib_id "antmicroCapacitorsmisc:C_100n_0201") (at 55.245 232.41 270) (unit 1)
    (in_bom yes) (on_board yes) (dnp no)
    (property "Reference" "C302" (at 55.245 233.045 90)
      (effects (font (size 1.524 1.524)) (justify left))
    )
    (property "Value" "C_100n_0201" (at 45.085 252.73 0)
      (effects (font (size 1.27 1.27) (thickness 0.15)) (justify left bottom) hide)
    )
    (property "Footprint" "antmicro-footprints:C_0201" (at 42.545 252.73 0)
      (effects (font (size 1.27 1.27) (thickness 0.15)) (justify left bottom) hide)
    )
    (property "Datasheet" " " (at 40.005 252.73 0)
      (effects (font (size 1.27 1.27) (thickness 0.15)) (justify left bottom) hide)
    )
    (property "Manufacturer" "Yaego" (at 34.925 252.73 0)
      (effects (font (size 1.27 1.27) (thickness 0.15)) (justify left bottom) hide)
    )
    (property "MPN" "CC0201KRX6S5BB104" (at 37.465 252.73 0)
      (effects (font (size 1.27 1.27) (thickness 0.15)) (justify left bottom) hide)
    )
    (property "Val" "100n" (at 55.245 236.855 90)
      (effects (font (size 1.27 1.27) (thickness 0.15)) (justify left))
    )
    (property "License" "Apache-2.0" (at 32.385 252.73 0)
      (effects (font (size 1.27 1.27) (thickness 0.15)) (justify left bottom) hide)
    )
    (property "Author" "Antmicro" (at 29.845 252.73 0)
      (effects (font (size 1.27 1.27) (thickness 0.15)) (justify left bottom) hide)
    )
    (property "Voltage" "" (at 27.305 252.73 0)
      (effects (font (size 1.27 1.27)) (justify left bottom) hide)
    )
    (property "Dielectric" "" (at 24.765 252.73 0)
      (effects (font (size 1.27 1.27)) (justify left bottom) hide)
    )
    (pin "1")
    (pin "2")
    (instances
      (project "data-center-rdimm-ddr4-tester"
        (path ""
          (reference "C302") (unit 1)
        )
      )
    )
  )

  (symbol (lib_id "antmicroCapacitorsmisc:C_100n_0201") (at 122.555 201.295 270) (unit 1)
    (in_bom yes) (on_board yes) (dnp no)
    (property "Reference" "C298" (at 122.555 201.93 90)
      (effects (font (size 1.524 1.524)) (justify left))
    )
    (property "Value" "C_100n_0201" (at 112.395 221.615 0)
      (effects (font (size 1.27 1.27) (thickness 0.15)) (justify left bottom) hide)
    )
    (property "Footprint" "antmicro-footprints:C_0201" (at 109.855 221.615 0)
      (effects (font (size 1.27 1.27) (thickness 0.15)) (justify left bottom) hide)
    )
    (property "Datasheet" " " (at 107.315 221.615 0)
      (effects (font (size 1.27 1.27) (thickness 0.15)) (justify left bottom) hide)
    )
    (property "Manufacturer" "Yaego" (at 102.235 221.615 0)
      (effects (font (size 1.27 1.27) (thickness 0.15)) (justify left bottom) hide)
    )
    (property "MPN" "CC0201KRX6S5BB104" (at 104.775 221.615 0)
      (effects (font (size 1.27 1.27) (thickness 0.15)) (justify left bottom) hide)
    )
    (property "Val" "100n" (at 122.555 205.74 90)
      (effects (font (size 1.27 1.27) (thickness 0.15)) (justify left))
    )
    (property "License" "Apache-2.0" (at 99.695 221.615 0)
      (effects (font (size 1.27 1.27) (thickness 0.15)) (justify left bottom) hide)
    )
    (property "Author" "Antmicro" (at 97.155 221.615 0)
      (effects (font (size 1.27 1.27) (thickness 0.15)) (justify left bottom) hide)
    )
    (property "Voltage" "" (at 94.615 221.615 0)
      (effects (font (size 1.27 1.27)) (justify left bottom) hide)
    )
    (property "Dielectric" "" (at 92.075 221.615 0)
      (effects (font (size 1.27 1.27)) (justify left bottom) hide)
    )
    (pin "1")
    (pin "2")
    (instances
      (project "data-center-rdimm-ddr4-tester"
        (path ""
          (reference "C298") (unit 1)
        )
      )
    )
  )

  (symbol (lib_id "antmicroCapacitors0402:C_100n_0402") (at 318.77 111.125 270) (unit 1)
    (in_bom yes) (on_board yes) (dnp no)
    (property "Reference" "C314" (at 319.405 111.76 90)
      (effects (font (size 1.524 1.524)) (justify left))
    )
    (property "Value" "C_100n_0402" (at 308.61 131.445 0)
      (effects (font (size 1.27 1.27) (thickness 0.15)) (justify left bottom) hide)
    )
    (property "Footprint" "antmicro-footprints:C_0402_1005Metric" (at 306.07 131.445 0)
      (effects (font (size 1.27 1.27) (thickness 0.15)) (justify left bottom) hide)
    )
    (property "Datasheet" "https://search.murata.co.jp/Ceramy/image/img/A01X/G101/ENG/GRM155R61H104KE14-01.pdf" (at 303.53 131.445 0)
      (effects (font (size 1.27 1.27) (thickness 0.15)) (justify left bottom) hide)
    )
    (property "Manufacturer" "Murata" (at 298.45 131.445 0)
      (effects (font (size 1.27 1.27) (thickness 0.15)) (justify left bottom) hide)
    )
    (property "MPN" "GRM155R61H104KE14D" (at 300.99 131.445 0)
      (effects (font (size 1.27 1.27) (thickness 0.15)) (justify left bottom) hide)
    )
    (property "Val" "100n" (at 319.405 115.57 90)
      (effects (font (size 1.27 1.27) (thickness 0.15)) (justify left))
    )
    (property "License" "Apache-2.0" (at 295.91 131.445 0)
      (effects (font (size 1.27 1.27) (thickness 0.15)) (justify left bottom) hide)
    )
    (property "Author" "Antmicro" (at 293.37 131.445 0)
      (effects (font (size 1.27 1.27) (thickness 0.15)) (justify left bottom) hide)
    )
    (property "Voltage" "50V" (at 290.83 131.445 0)
      (effects (font (size 1.27 1.27)) (justify left bottom) hide)
    )
    (property "Dielectric" "X5R" (at 288.29 131.445 0)
      (effects (font (size 1.27 1.27)) (justify left bottom) hide)
    )
    (pin "1")
    (pin "2")
    (instances
      (project "data-center-rdimm-ddr4-tester"
        (path ""
          (reference "C314") (unit 1)
        )
      )
    )
  )

  (symbol (lib_id "antmicroCapacitors0402:C_100n_0402") (at 142.24 135.255 270) (unit 1)
    (in_bom yes) (on_board yes) (dnp no)
    (property "Reference" "C313" (at 142.24 135.89 90)
      (effects (font (size 1.524 1.524)) (justify left))
    )
    (property "Value" "C_100n_0402" (at 132.08 155.575 0)
      (effects (font (size 1.27 1.27) (thickness 0.15)) (justify left bottom) hide)
    )
    (property "Footprint" "antmicro-footprints:C_0402_1005Metric" (at 129.54 155.575 0)
      (effects (font (size 1.27 1.27) (thickness 0.15)) (justify left bottom) hide)
    )
    (property "Datasheet" "https://search.murata.co.jp/Ceramy/image/img/A01X/G101/ENG/GRM155R61H104KE14-01.pdf" (at 127 155.575 0)
      (effects (font (size 1.27 1.27) (thickness 0.15)) (justify left bottom) hide)
    )
    (property "Manufacturer" "Murata" (at 121.92 155.575 0)
      (effects (font (size 1.27 1.27) (thickness 0.15)) (justify left bottom) hide)
    )
    (property "MPN" "GRM155R61H104KE14D" (at 124.46 155.575 0)
      (effects (font (size 1.27 1.27) (thickness 0.15)) (justify left bottom) hide)
    )
    (property "Val" "100n" (at 142.24 139.7 90)
      (effects (font (size 1.27 1.27) (thickness 0.15)) (justify left))
    )
    (property "License" "Apache-2.0" (at 119.38 155.575 0)
      (effects (font (size 1.27 1.27) (thickness 0.15)) (justify left bottom) hide)
    )
    (property "Author" "Antmicro" (at 116.84 155.575 0)
      (effects (font (size 1.27 1.27) (thickness 0.15)) (justify left bottom) hide)
    )
    (property "Voltage" "50V" (at 114.3 155.575 0)
      (effects (font (size 1.27 1.27)) (justify left bottom) hide)
    )
    (property "Dielectric" "X5R" (at 111.76 155.575 0)
      (effects (font (size 1.27 1.27)) (justify left bottom) hide)
    )
    (pin "1")
    (pin "2")
    (instances
      (project "data-center-rdimm-ddr4-tester"
        (path ""
          (reference "C313") (unit 1)
        )
      )
    )
  )

  (symbol (lib_id "antmicroCapacitorsmisc:C_100n_0201") (at 95.885 201.295 270) (unit 1)
    (in_bom yes) (on_board yes) (dnp no)
    (property "Reference" "C92" (at 95.885 201.93 90)
      (effects (font (size 1.524 1.524)) (justify left))
    )
    (property "Value" "C_100n_0201" (at 85.725 221.615 0)
      (effects (font (size 1.27 1.27) (thickness 0.15)) (justify left bottom) hide)
    )
    (property "Footprint" "antmicro-footprints:C_0201" (at 83.185 221.615 0)
      (effects (font (size 1.27 1.27) (thickness 0.15)) (justify left bottom) hide)
    )
    (property "Datasheet" " " (at 80.645 221.615 0)
      (effects (font (size 1.27 1.27) (thickness 0.15)) (justify left bottom) hide)
    )
    (property "Manufacturer" "Yaego" (at 75.565 221.615 0)
      (effects (font (size 1.27 1.27) (thickness 0.15)) (justify left bottom) hide)
    )
    (property "MPN" "CC0201KRX6S5BB104" (at 78.105 221.615 0)
      (effects (font (size 1.27 1.27) (thickness 0.15)) (justify left bottom) hide)
    )
    (property "Val" "100n" (at 95.885 205.74 90)
      (effects (font (size 1.27 1.27) (thickness 0.15)) (justify left))
    )
    (property "License" "Apache-2.0" (at 73.025 221.615 0)
      (effects (font (size 1.27 1.27) (thickness 0.15)) (justify left bottom) hide)
    )
    (property "Author" "Antmicro" (at 70.485 221.615 0)
      (effects (font (size 1.27 1.27) (thickness 0.15)) (justify left bottom) hide)
    )
    (property "Voltage" "" (at 67.945 221.615 0)
      (effects (font (size 1.27 1.27)) (justify left bottom) hide)
    )
    (property "Dielectric" "" (at 65.405 221.615 0)
      (effects (font (size 1.27 1.27)) (justify left bottom) hide)
    )
    (pin "1")
    (pin "2")
    (instances
      (project "data-center-rdimm-ddr4-tester"
        (path ""
          (reference "C92") (unit 1)
        )
      )
    )
  )

  (symbol (lib_id "antmicropower:GND") (at 68.58 237.49 0) (unit 1)
    (in_bom yes) (on_board yes) (dnp no) (fields_autoplaced)
    (property "Reference" "#PWR0387" (at 68.58 243.84 0)
      (effects (font (size 1.27 1.27)) hide)
    )
    (property "Value" "GND" (at 68.58 241.935 0)
      (effects (font (size 1.27 1.27)))
    )
    (property "Footprint" "" (at 68.58 237.49 0)
      (effects (font (size 1.27 1.27)) hide)
    )
    (property "Datasheet" "" (at 68.58 237.49 0)
      (effects (font (size 1.27 1.27)) hide)
    )
    (property "Author" "Antmicro" (at 77.47 245.11 0)
      (effects (font (size 1.27 1.27) (thickness 0.15)) (justify left bottom) hide)
    )
    (property "License" "Apache-2.0" (at 77.47 247.65 0)
      (effects (font (size 1.27 1.27) (thickness 0.15)) (justify left bottom) hide)
    )
    (pin "1")
    (instances
      (project "data-center-rdimm-ddr4-tester"
        (path ""
          (reference "#PWR0387") (unit 1)
        )
      )
    )
  )

  (symbol (lib_id "antmicroCapacitorsmisc:C_100n_0201") (at 135.89 201.295 270) (unit 1)
    (in_bom yes) (on_board yes) (dnp no)
    (property "Reference" "C300" (at 135.89 201.93 90)
      (effects (font (size 1.524 1.524)) (justify left))
    )
    (property "Value" "C_100n_0201" (at 125.73 221.615 0)
      (effects (font (size 1.27 1.27) (thickness 0.15)) (justify left bottom) hide)
    )
    (property "Footprint" "antmicro-footprints:C_0201" (at 123.19 221.615 0)
      (effects (font (size 1.27 1.27) (thickness 0.15)) (justify left bottom) hide)
    )
    (property "Datasheet" " " (at 120.65 221.615 0)
      (effects (font (size 1.27 1.27) (thickness 0.15)) (justify left bottom) hide)
    )
    (property "Manufacturer" "Yaego" (at 115.57 221.615 0)
      (effects (font (size 1.27 1.27) (thickness 0.15)) (justify left bottom) hide)
    )
    (property "MPN" "CC0201KRX6S5BB104" (at 118.11 221.615 0)
      (effects (font (size 1.27 1.27) (thickness 0.15)) (justify left bottom) hide)
    )
    (property "Val" "100n" (at 135.89 205.74 90)
      (effects (font (size 1.27 1.27) (thickness 0.15)) (justify left))
    )
    (property "License" "Apache-2.0" (at 113.03 221.615 0)
      (effects (font (size 1.27 1.27) (thickness 0.15)) (justify left bottom) hide)
    )
    (property "Author" "Antmicro" (at 110.49 221.615 0)
      (effects (font (size 1.27 1.27) (thickness 0.15)) (justify left bottom) hide)
    )
    (property "Voltage" "" (at 107.95 221.615 0)
      (effects (font (size 1.27 1.27)) (justify left bottom) hide)
    )
    (property "Dielectric" "" (at 105.41 221.615 0)
      (effects (font (size 1.27 1.27)) (justify left bottom) hide)
    )
    (pin "1")
    (pin "2")
    (instances
      (project "data-center-rdimm-ddr4-tester"
        (path ""
          (reference "C300") (unit 1)
        )
      )
    )
  )

  (symbol (lib_id "antmicropower:GND") (at 75.565 237.49 0) (unit 1)
    (in_bom yes) (on_board yes) (dnp no) (fields_autoplaced)
    (property "Reference" "#PWR0386" (at 75.565 243.84 0)
      (effects (font (size 1.27 1.27)) hide)
    )
    (property "Value" "GND" (at 75.565 241.935 0)
      (effects (font (size 1.27 1.27)))
    )
    (property "Footprint" "" (at 75.565 237.49 0)
      (effects (font (size 1.27 1.27)) hide)
    )
    (property "Datasheet" "" (at 75.565 237.49 0)
      (effects (font (size 1.27 1.27)) hide)
    )
    (property "Author" "Antmicro" (at 84.455 245.11 0)
      (effects (font (size 1.27 1.27) (thickness 0.15)) (justify left bottom) hide)
    )
    (property "License" "Apache-2.0" (at 84.455 247.65 0)
      (effects (font (size 1.27 1.27) (thickness 0.15)) (justify left bottom) hide)
    )
    (pin "1")
    (instances
      (project "data-center-rdimm-ddr4-tester"
        (path ""
          (reference "#PWR0386") (unit 1)
        )
      )
    )
  )

  (symbol (lib_id "antmicropower:GND") (at 92.71 175.26 0) (unit 1)
    (in_bom yes) (on_board yes) (dnp no) (fields_autoplaced)
    (property "Reference" "#PWR0374" (at 92.71 181.61 0)
      (effects (font (size 1.27 1.27)) hide)
    )
    (property "Value" "GND" (at 92.71 180.34 0)
      (effects (font (size 1.27 1.27)))
    )
    (property "Footprint" "" (at 92.71 175.26 0)
      (effects (font (size 1.27 1.27)) hide)
    )
    (property "Datasheet" "" (at 92.71 175.26 0)
      (effects (font (size 1.27 1.27)) hide)
    )
    (property "Author" "Antmicro" (at 101.6 182.88 0)
      (effects (font (size 1.27 1.27) (thickness 0.15)) (justify left bottom) hide)
    )
    (property "License" "Apache-2.0" (at 101.6 185.42 0)
      (effects (font (size 1.27 1.27) (thickness 0.15)) (justify left bottom) hide)
    )
    (pin "1")
    (instances
      (project "data-center-rdimm-ddr4-tester"
        (path ""
          (reference "#PWR0374") (unit 1)
        )
      )
    )
  )

  (symbol (lib_id "antmicroCapacitorsmisc:C_100n_0201") (at 349.25 111.125 270) (unit 1)
    (in_bom yes) (on_board yes) (dnp no)
    (property "Reference" "C251" (at 349.885 111.76 90)
      (effects (font (size 1.524 1.524)) (justify left))
    )
    (property "Value" "C_100n_0201" (at 339.09 131.445 0)
      (effects (font (size 1.27 1.27) (thickness 0.15)) (justify left bottom) hide)
    )
    (property "Footprint" "antmicro-footprints:C_0201" (at 336.55 131.445 0)
      (effects (font (size 1.27 1.27) (thickness 0.15)) (justify left bottom) hide)
    )
    (property "Datasheet" " " (at 334.01 131.445 0)
      (effects (font (size 1.27 1.27) (thickness 0.15)) (justify left bottom) hide)
    )
    (property "Manufacturer" "Yaego" (at 328.93 131.445 0)
      (effects (font (size 1.27 1.27) (thickness 0.15)) (justify left bottom) hide)
    )
    (property "MPN" "CC0201KRX6S5BB104" (at 331.47 131.445 0)
      (effects (font (size 1.27 1.27) (thickness 0.15)) (justify left bottom) hide)
    )
    (property "Val" "100n" (at 349.885 115.57 90)
      (effects (font (size 1.27 1.27) (thickness 0.15)) (justify left))
    )
    (property "License" "Apache-2.0" (at 326.39 131.445 0)
      (effects (font (size 1.27 1.27) (thickness 0.15)) (justify left bottom) hide)
    )
    (property "Author" "Antmicro" (at 323.85 131.445 0)
      (effects (font (size 1.27 1.27) (thickness 0.15)) (justify left bottom) hide)
    )
    (property "Voltage" "" (at 321.31 131.445 0)
      (effects (font (size 1.27 1.27)) (justify left bottom) hide)
    )
    (property "Dielectric" "" (at 318.77 131.445 0)
      (effects (font (size 1.27 1.27)) (justify left bottom) hide)
    )
    (pin "1")
    (pin "2")
    (instances
      (project "data-center-rdimm-ddr4-tester"
        (path ""
          (reference "C251") (unit 1)
        )
      )
    )
  )

  (symbol (lib_id "antmicroCapacitorsmisc:C_100n_0201") (at 326.39 111.125 270) (unit 1)
    (in_bom yes) (on_board yes) (dnp no)
    (property "Reference" "C248" (at 327.025 111.76 90)
      (effects (font (size 1.524 1.524)) (justify left))
    )
    (property "Value" "C_100n_0201" (at 316.23 131.445 0)
      (effects (font (size 1.27 1.27) (thickness 0.15)) (justify left bottom) hide)
    )
    (property "Footprint" "antmicro-footprints:C_0201" (at 313.69 131.445 0)
      (effects (font (size 1.27 1.27) (thickness 0.15)) (justify left bottom) hide)
    )
    (property "Datasheet" " " (at 311.15 131.445 0)
      (effects (font (size 1.27 1.27) (thickness 0.15)) (justify left bottom) hide)
    )
    (property "Manufacturer" "Yaego" (at 306.07 131.445 0)
      (effects (font (size 1.27 1.27) (thickness 0.15)) (justify left bottom) hide)
    )
    (property "MPN" "CC0201KRX6S5BB104" (at 308.61 131.445 0)
      (effects (font (size 1.27 1.27) (thickness 0.15)) (justify left bottom) hide)
    )
    (property "Val" "100n" (at 327.025 115.57 90)
      (effects (font (size 1.27 1.27) (thickness 0.15)) (justify left))
    )
    (property "License" "Apache-2.0" (at 303.53 131.445 0)
      (effects (font (size 1.27 1.27) (thickness 0.15)) (justify left bottom) hide)
    )
    (property "Author" "Antmicro" (at 300.99 131.445 0)
      (effects (font (size 1.27 1.27) (thickness 0.15)) (justify left bottom) hide)
    )
    (property "Voltage" "" (at 298.45 131.445 0)
      (effects (font (size 1.27 1.27)) (justify left bottom) hide)
    )
    (property "Dielectric" "" (at 295.91 131.445 0)
      (effects (font (size 1.27 1.27)) (justify left bottom) hide)
    )
    (pin "1")
    (pin "2")
    (instances
      (project "data-center-rdimm-ddr4-tester"
        (path ""
          (reference "C248") (unit 1)
        )
      )
    )
  )

  (symbol (lib_id "antmicroCapacitorsmisc:C_100n_0201") (at 85.725 170.18 270) (unit 1)
    (in_bom yes) (on_board yes) (dnp no)
    (property "Reference" "C296" (at 85.725 170.815 90)
      (effects (font (size 1.524 1.524)) (justify left))
    )
    (property "Value" "C_100n_0201" (at 75.565 190.5 0)
      (effects (font (size 1.27 1.27) (thickness 0.15)) (justify left bottom) hide)
    )
    (property "Footprint" "antmicro-footprints:C_0201" (at 73.025 190.5 0)
      (effects (font (size 1.27 1.27) (thickness 0.15)) (justify left bottom) hide)
    )
    (property "Datasheet" " " (at 70.485 190.5 0)
      (effects (font (size 1.27 1.27) (thickness 0.15)) (justify left bottom) hide)
    )
    (property "Manufacturer" "Yaego" (at 65.405 190.5 0)
      (effects (font (size 1.27 1.27) (thickness 0.15)) (justify left bottom) hide)
    )
    (property "MPN" "CC0201KRX6S5BB104" (at 67.945 190.5 0)
      (effects (font (size 1.27 1.27) (thickness 0.15)) (justify left bottom) hide)
    )
    (property "Val" "100n" (at 85.725 174.625 90)
      (effects (font (size 1.27 1.27) (thickness 0.15)) (justify left))
    )
    (property "License" "Apache-2.0" (at 62.865 190.5 0)
      (effects (font (size 1.27 1.27) (thickness 0.15)) (justify left bottom) hide)
    )
    (property "Author" "Antmicro" (at 60.325 190.5 0)
      (effects (font (size 1.27 1.27) (thickness 0.15)) (justify left bottom) hide)
    )
    (property "Voltage" "" (at 57.785 190.5 0)
      (effects (font (size 1.27 1.27)) (justify left bottom) hide)
    )
    (property "Dielectric" "" (at 55.245 190.5 0)
      (effects (font (size 1.27 1.27)) (justify left bottom) hide)
    )
    (pin "1")
    (pin "2")
    (instances
      (project "data-center-rdimm-ddr4-tester"
        (path ""
          (reference "C296") (unit 1)
        )
      )
    )
  )

  (symbol (lib_id "antmicroCapacitorsmisc:C_100n_0201") (at 78.74 170.18 270) (unit 1)
    (in_bom yes) (on_board yes) (dnp no)
    (property "Reference" "C295" (at 78.74 170.815 90)
      (effects (font (size 1.524 1.524)) (justify left))
    )
    (property "Value" "C_100n_0201" (at 68.58 190.5 0)
      (effects (font (size 1.27 1.27) (thickness 0.15)) (justify left bottom) hide)
    )
    (property "Footprint" "antmicro-footprints:C_0201" (at 66.04 190.5 0)
      (effects (font (size 1.27 1.27) (thickness 0.15)) (justify left bottom) hide)
    )
    (property "Datasheet" " " (at 63.5 190.5 0)
      (effects (font (size 1.27 1.27) (thickness 0.15)) (justify left bottom) hide)
    )
    (property "Manufacturer" "Yaego" (at 58.42 190.5 0)
      (effects (font (size 1.27 1.27) (thickness 0.15)) (justify left bottom) hide)
    )
    (property "MPN" "CC0201KRX6S5BB104" (at 60.96 190.5 0)
      (effects (font (size 1.27 1.27) (thickness 0.15)) (justify left bottom) hide)
    )
    (property "Val" "100n" (at 78.74 174.625 90)
      (effects (font (size 1.27 1.27) (thickness 0.15)) (justify left))
    )
    (property "License" "Apache-2.0" (at 55.88 190.5 0)
      (effects (font (size 1.27 1.27) (thickness 0.15)) (justify left bottom) hide)
    )
    (property "Author" "Antmicro" (at 53.34 190.5 0)
      (effects (font (size 1.27 1.27) (thickness 0.15)) (justify left bottom) hide)
    )
    (property "Voltage" "" (at 50.8 190.5 0)
      (effects (font (size 1.27 1.27)) (justify left bottom) hide)
    )
    (property "Dielectric" "" (at 48.26 190.5 0)
      (effects (font (size 1.27 1.27)) (justify left bottom) hide)
    )
    (pin "1")
    (pin "2")
    (instances
      (project "data-center-rdimm-ddr4-tester"
        (path ""
          (reference "C295") (unit 1)
        )
      )
    )
  )

  (symbol (lib_id "antmicropower:GND") (at 37.465 140.335 0) (unit 1)
    (in_bom yes) (on_board yes) (dnp no) (fields_autoplaced)
    (property "Reference" "#PWR0244" (at 37.465 146.685 0)
      (effects (font (size 1.27 1.27)) hide)
    )
    (property "Value" "GND" (at 37.465 144.78 0)
      (effects (font (size 1.27 1.27)))
    )
    (property "Footprint" "" (at 37.465 140.335 0)
      (effects (font (size 1.27 1.27)) hide)
    )
    (property "Datasheet" "" (at 37.465 140.335 0)
      (effects (font (size 1.27 1.27)) hide)
    )
    (property "Author" "Antmicro" (at 46.355 147.955 0)
      (effects (font (size 1.27 1.27) (thickness 0.15)) (justify left bottom) hide)
    )
    (property "License" "Apache-2.0" (at 46.355 150.495 0)
      (effects (font (size 1.27 1.27) (thickness 0.15)) (justify left bottom) hide)
    )
    (pin "1")
    (instances
      (project "data-center-rdimm-ddr4-tester"
        (path ""
          (reference "#PWR0244") (unit 1)
        )
      )
    )
  )

  (symbol (lib_id "antmicropower:GND") (at 99.695 175.26 0) (unit 1)
    (in_bom yes) (on_board yes) (dnp no) (fields_autoplaced)
    (property "Reference" "#PWR0243" (at 99.695 181.61 0)
      (effects (font (size 1.27 1.27)) hide)
    )
    (property "Value" "GND" (at 99.695 180.34 0)
      (effects (font (size 1.27 1.27)))
    )
    (property "Footprint" "" (at 99.695 175.26 0)
      (effects (font (size 1.27 1.27)) hide)
    )
    (property "Datasheet" "" (at 99.695 175.26 0)
      (effects (font (size 1.27 1.27)) hide)
    )
    (property "Author" "Antmicro" (at 108.585 182.88 0)
      (effects (font (size 1.27 1.27) (thickness 0.15)) (justify left bottom) hide)
    )
    (property "License" "Apache-2.0" (at 108.585 185.42 0)
      (effects (font (size 1.27 1.27) (thickness 0.15)) (justify left bottom) hide)
    )
    (pin "1")
    (instances
      (project "data-center-rdimm-ddr4-tester"
        (path ""
          (reference "#PWR0243") (unit 1)
        )
      )
    )
  )

  (symbol (lib_id "antmicropower:GND") (at 71.755 175.26 0) (unit 1)
    (in_bom yes) (on_board yes) (dnp no) (fields_autoplaced)
    (property "Reference" "#PWR0375" (at 71.755 181.61 0)
      (effects (font (size 1.27 1.27)) hide)
    )
    (property "Value" "GND" (at 71.755 179.705 0)
      (effects (font (size 1.27 1.27)))
    )
    (property "Footprint" "" (at 71.755 175.26 0)
      (effects (font (size 1.27 1.27)) hide)
    )
    (property "Datasheet" "" (at 71.755 175.26 0)
      (effects (font (size 1.27 1.27)) hide)
    )
    (property "Author" "Antmicro" (at 80.645 182.88 0)
      (effects (font (size 1.27 1.27) (thickness 0.15)) (justify left bottom) hide)
    )
    (property "License" "Apache-2.0" (at 80.645 185.42 0)
      (effects (font (size 1.27 1.27) (thickness 0.15)) (justify left bottom) hide)
    )
    (pin "1")
    (instances
      (project "data-center-rdimm-ddr4-tester"
        (path ""
          (reference "#PWR0375") (unit 1)
        )
      )
    )
  )

  (symbol (lib_id "antmicropower:GND") (at 371.475 116.205 0) (unit 1)
    (in_bom yes) (on_board yes) (dnp no) (fields_autoplaced)
    (property "Reference" "#PWR0214" (at 371.475 122.555 0)
      (effects (font (size 1.27 1.27)) hide)
    )
    (property "Value" "GND" (at 371.475 120.65 0)
      (effects (font (size 1.27 1.27)))
    )
    (property "Footprint" "" (at 371.475 116.205 0)
      (effects (font (size 1.27 1.27)) hide)
    )
    (property "Datasheet" "" (at 371.475 116.205 0)
      (effects (font (size 1.27 1.27)) hide)
    )
    (property "Author" "Antmicro" (at 380.365 123.825 0)
      (effects (font (size 1.27 1.27) (thickness 0.15)) (justify left bottom) hide)
    )
    (property "License" "Apache-2.0" (at 380.365 126.365 0)
      (effects (font (size 1.27 1.27) (thickness 0.15)) (justify left bottom) hide)
    )
    (pin "1")
    (instances
      (project "data-center-rdimm-ddr4-tester"
        (path ""
          (reference "#PWR0214") (unit 1)
        )
      )
    )
  )

  (symbol (lib_id "antmicroCapacitorsmisc:C_100n_0201") (at 50.8 170.18 270) (unit 1)
    (in_bom yes) (on_board yes) (dnp no)
    (property "Reference" "C278" (at 50.8 170.815 90)
      (effects (font (size 1.524 1.524)) (justify left))
    )
    (property "Value" "C_100n_0201" (at 40.64 190.5 0)
      (effects (font (size 1.27 1.27) (thickness 0.15)) (justify left bottom) hide)
    )
    (property "Footprint" "antmicro-footprints:C_0201" (at 38.1 190.5 0)
      (effects (font (size 1.27 1.27) (thickness 0.15)) (justify left bottom) hide)
    )
    (property "Datasheet" " " (at 35.56 190.5 0)
      (effects (font (size 1.27 1.27) (thickness 0.15)) (justify left bottom) hide)
    )
    (property "Manufacturer" "Yaego" (at 30.48 190.5 0)
      (effects (font (size 1.27 1.27) (thickness 0.15)) (justify left bottom) hide)
    )
    (property "MPN" "CC0201KRX6S5BB104" (at 33.02 190.5 0)
      (effects (font (size 1.27 1.27) (thickness 0.15)) (justify left bottom) hide)
    )
    (property "Val" "100n" (at 50.8 174.625 90)
      (effects (font (size 1.27 1.27) (thickness 0.15)) (justify left))
    )
    (property "License" "Apache-2.0" (at 27.94 190.5 0)
      (effects (font (size 1.27 1.27) (thickness 0.15)) (justify left bottom) hide)
    )
    (property "Author" "Antmicro" (at 25.4 190.5 0)
      (effects (font (size 1.27 1.27) (thickness 0.15)) (justify left bottom) hide)
    )
    (property "Voltage" "" (at 22.86 190.5 0)
      (effects (font (size 1.27 1.27)) (justify left bottom) hide)
    )
    (property "Dielectric" "" (at 20.32 190.5 0)
      (effects (font (size 1.27 1.27)) (justify left bottom) hide)
    )
    (pin "1")
    (pin "2")
    (instances
      (project "data-center-rdimm-ddr4-tester"
        (path ""
          (reference "C278") (unit 1)
        )
      )
    )
  )

  (symbol (lib_id "antmicroResistors0402:R_100R_0402") (at 320.675 76.835 90) (unit 1)
    (in_bom yes) (on_board yes) (dnp no) (fields_autoplaced)
    (property "Reference" "R207" (at 322.58 73.025 90)
      (effects (font (size 1.524 1.524)) (justify right))
    )
    (property "Value" "R_100R_0402" (at 333.375 56.515 0)
      (effects (font (size 1.27 1.27) (thickness 0.15)) (justify left bottom) hide)
    )
    (property "Footprint" "antmicro-footprints:R_0402_1005Metric" (at 335.915 56.515 0)
      (effects (font (size 1.27 1.27) (thickness 0.15)) (justify left bottom) hide)
    )
    (property "Datasheet" "https://www.bourns.com/docs/product-datasheets/cr.pdf" (at 338.455 56.515 0)
      (effects (font (size 1.27 1.27) (thickness 0.15)) (justify left bottom) hide)
    )
    (property "Manufacturer" "Bourns" (at 343.535 56.515 0)
      (effects (font (size 1.27 1.27) (thickness 0.15)) (justify left bottom) hide)
    )
    (property "MPN" "CR0402-FX-1000GLF" (at 340.995 56.515 0)
      (effects (font (size 1.27 1.27) (thickness 0.15)) (justify left bottom) hide)
    )
    (property "Val" "100R" (at 322.58 76.1999 90)
      (effects (font (size 1.27 1.27) (thickness 0.15)) (justify right))
    )
    (property "License" "Apache-2.0" (at 346.075 56.515 0)
      (effects (font (size 1.27 1.27) (thickness 0.15)) (justify left bottom) hide)
    )
    (property "Author" "Antmicro" (at 348.615 56.515 0)
      (effects (font (size 1.27 1.27) (thickness 0.15)) (justify left bottom) hide)
    )
    (property "Tolerance" "1%" (at 330.835 56.515 0)
      (effects (font (size 1.27 1.27)) (justify left bottom) hide)
    )
    (pin "1")
    (pin "2")
    (instances
      (project "data-center-rdimm-ddr4-tester"
        (path ""
          (reference "R207") (unit 1)
        )
      )
    )
  )

  (symbol (lib_id "antmicroCapacitorsmisc:C_100n_0201") (at 43.815 170.18 270) (unit 1)
    (in_bom yes) (on_board yes) (dnp no)
    (property "Reference" "C277" (at 43.815 170.815 90)
      (effects (font (size 1.524 1.524)) (justify left))
    )
    (property "Value" "C_100n_0201" (at 33.655 190.5 0)
      (effects (font (size 1.27 1.27) (thickness 0.15)) (justify left bottom) hide)
    )
    (property "Footprint" "antmicro-footprints:C_0201" (at 31.115 190.5 0)
      (effects (font (size 1.27 1.27) (thickness 0.15)) (justify left bottom) hide)
    )
    (property "Datasheet" " " (at 28.575 190.5 0)
      (effects (font (size 1.27 1.27) (thickness 0.15)) (justify left bottom) hide)
    )
    (property "Manufacturer" "Yaego" (at 23.495 190.5 0)
      (effects (font (size 1.27 1.27) (thickness 0.15)) (justify left bottom) hide)
    )
    (property "MPN" "CC0201KRX6S5BB104" (at 26.035 190.5 0)
      (effects (font (size 1.27 1.27) (thickness 0.15)) (justify left bottom) hide)
    )
    (property "Val" "100n" (at 43.815 174.625 90)
      (effects (font (size 1.27 1.27) (thickness 0.15)) (justify left))
    )
    (property "License" "Apache-2.0" (at 20.955 190.5 0)
      (effects (font (size 1.27 1.27) (thickness 0.15)) (justify left bottom) hide)
    )
    (property "Author" "Antmicro" (at 18.415 190.5 0)
      (effects (font (size 1.27 1.27) (thickness 0.15)) (justify left bottom) hide)
    )
    (property "Voltage" "" (at 15.875 190.5 0)
      (effects (font (size 1.27 1.27)) (justify left bottom) hide)
    )
    (property "Dielectric" "" (at 13.335 190.5 0)
      (effects (font (size 1.27 1.27)) (justify left bottom) hide)
    )
    (pin "1")
    (pin "2")
    (instances
      (project "data-center-rdimm-ddr4-tester"
        (path ""
          (reference "C277") (unit 1)
        )
      )
    )
  )

  (symbol (lib_id "antmicroCapacitors0603:C_47u_0603") (at 30.48 135.255 270) (unit 1)
    (in_bom yes) (on_board yes) (dnp no)
    (property "Reference" "C80" (at 30.48 135.89 90)
      (effects (font (size 1.524 1.524)) (justify left))
    )
    (property "Value" "C_47u_0603" (at 20.32 155.575 0)
      (effects (font (size 1.27 1.27) (thickness 0.15)) (justify left bottom) hide)
    )
    (property "Footprint" "antmicro-footprints:C_0603_1608Metric" (at 17.78 155.575 0)
      (effects (font (size 1.27 1.27) (thickness 0.15)) (justify left bottom) hide)
    )
    (property "Datasheet" " " (at 15.24 155.575 0)
      (effects (font (size 1.27 1.27) (thickness 0.15)) (justify left bottom) hide)
    )
    (property "Manufacturer" "Murata" (at 10.16 155.575 0)
      (effects (font (size 1.27 1.27) (thickness 0.15)) (justify left bottom) hide)
    )
    (property "MPN" "GRM188R60J476ME15D" (at 12.7 155.575 0)
      (effects (font (size 1.27 1.27) (thickness 0.15)) (justify left bottom) hide)
    )
    (property "Val" "47u" (at 30.48 139.7 90)
      (effects (font (size 1.27 1.27) (thickness 0.15)) (justify left))
    )
    (property "License" "Apache-2.0" (at 7.62 155.575 0)
      (effects (font (size 1.27 1.27) (thickness 0.15)) (justify left bottom) hide)
    )
    (property "Author" "Antmicro" (at 5.08 155.575 0)
      (effects (font (size 1.27 1.27) (thickness 0.15)) (justify left bottom) hide)
    )
    (property "Voltage" "" (at 2.54 155.575 0)
      (effects (font (size 1.27 1.27)) (justify left bottom) hide)
    )
    (property "Dielectric" "" (at 0 155.575 0)
      (effects (font (size 1.27 1.27)) (justify left bottom) hide)
    )
    (pin "1")
    (pin "2")
    (instances
      (project "data-center-rdimm-ddr4-tester"
        (path ""
          (reference "C80") (unit 1)
        )
      )
    )
  )

  (symbol (lib_id "antmicropower:GND") (at 85.725 175.26 0) (unit 1)
    (in_bom yes) (on_board yes) (dnp no) (fields_autoplaced)
    (property "Reference" "#PWR0373" (at 85.725 181.61 0)
      (effects (font (size 1.27 1.27)) hide)
    )
    (property "Value" "GND" (at 85.725 180.34 0)
      (effects (font (size 1.27 1.27)))
    )
    (property "Footprint" "" (at 85.725 175.26 0)
      (effects (font (size 1.27 1.27)) hide)
    )
    (property "Datasheet" "" (at 85.725 175.26 0)
      (effects (font (size 1.27 1.27)) hide)
    )
    (property "Author" "Antmicro" (at 94.615 182.88 0)
      (effects (font (size 1.27 1.27) (thickness 0.15)) (justify left bottom) hide)
    )
    (property "License" "Apache-2.0" (at 94.615 185.42 0)
      (effects (font (size 1.27 1.27) (thickness 0.15)) (justify left bottom) hide)
    )
    (pin "1")
    (instances
      (project "data-center-rdimm-ddr4-tester"
        (path ""
          (reference "#PWR0373") (unit 1)
        )
      )
    )
  )

  (symbol (lib_id "antmicropower:GND") (at 142.24 140.335 0) (unit 1)
    (in_bom yes) (on_board yes) (dnp no) (fields_autoplaced)
    (property "Reference" "#PWR0397" (at 142.24 146.685 0)
      (effects (font (size 1.27 1.27)) hide)
    )
    (property "Value" "GND" (at 142.24 144.78 0)
      (effects (font (size 1.27 1.27)))
    )
    (property "Footprint" "" (at 142.24 140.335 0)
      (effects (font (size 1.27 1.27)) hide)
    )
    (property "Datasheet" "" (at 142.24 140.335 0)
      (effects (font (size 1.27 1.27)) hide)
    )
    (property "Author" "Antmicro" (at 151.13 147.955 0)
      (effects (font (size 1.27 1.27) (thickness 0.15)) (justify left bottom) hide)
    )
    (property "License" "Apache-2.0" (at 151.13 150.495 0)
      (effects (font (size 1.27 1.27) (thickness 0.15)) (justify left bottom) hide)
    )
    (pin "1")
    (instances
      (project "data-center-rdimm-ddr4-tester"
        (path ""
          (reference "#PWR0397") (unit 1)
        )
      )
    )
  )

  (symbol (lib_id "antmicroCapacitorsmisc:C_100n_0201") (at 262.89 111.125 270) (unit 1)
    (in_bom yes) (on_board yes) (dnp no)
    (property "Reference" "C241" (at 263.525 111.76 90)
      (effects (font (size 1.524 1.524)) (justify left))
    )
    (property "Value" "C_100n_0201" (at 252.73 131.445 0)
      (effects (font (size 1.27 1.27) (thickness 0.15)) (justify left bottom) hide)
    )
    (property "Footprint" "antmicro-footprints:C_0201" (at 250.19 131.445 0)
      (effects (font (size 1.27 1.27) (thickness 0.15)) (justify left bottom) hide)
    )
    (property "Datasheet" " " (at 247.65 131.445 0)
      (effects (font (size 1.27 1.27) (thickness 0.15)) (justify left bottom) hide)
    )
    (property "Manufacturer" "Yaego" (at 242.57 131.445 0)
      (effects (font (size 1.27 1.27) (thickness 0.15)) (justify left bottom) hide)
    )
    (property "MPN" "CC0201KRX6S5BB104" (at 245.11 131.445 0)
      (effects (font (size 1.27 1.27) (thickness 0.15)) (justify left bottom) hide)
    )
    (property "Val" "100n" (at 263.525 115.57 90)
      (effects (font (size 1.27 1.27) (thickness 0.15)) (justify left))
    )
    (property "License" "Apache-2.0" (at 240.03 131.445 0)
      (effects (font (size 1.27 1.27) (thickness 0.15)) (justify left bottom) hide)
    )
    (property "Author" "Antmicro" (at 237.49 131.445 0)
      (effects (font (size 1.27 1.27) (thickness 0.15)) (justify left bottom) hide)
    )
    (property "Voltage" "" (at 234.95 131.445 0)
      (effects (font (size 1.27 1.27)) (justify left bottom) hide)
    )
    (property "Dielectric" "" (at 232.41 131.445 0)
      (effects (font (size 1.27 1.27)) (justify left bottom) hide)
    )
    (pin "1")
    (pin "2")
    (instances
      (project "data-center-rdimm-ddr4-tester"
        (path ""
          (reference "C241") (unit 1)
        )
      )
    )
  )

  (symbol (lib_id "antmicroCapacitorsmisc:C_100n_0201") (at 36.83 170.18 270) (unit 1)
    (in_bom yes) (on_board yes) (dnp no)
    (property "Reference" "C276" (at 37.465 170.815 90)
      (effects (font (size 1.524 1.524)) (justify left))
    )
    (property "Value" "C_100n_0201" (at 26.67 190.5 0)
      (effects (font (size 1.27 1.27) (thickness 0.15)) (justify left bottom) hide)
    )
    (property "Footprint" "antmicro-footprints:C_0201" (at 24.13 190.5 0)
      (effects (font (size 1.27 1.27) (thickness 0.15)) (justify left bottom) hide)
    )
    (property "Datasheet" " " (at 21.59 190.5 0)
      (effects (font (size 1.27 1.27) (thickness 0.15)) (justify left bottom) hide)
    )
    (property "Manufacturer" "Yaego" (at 16.51 190.5 0)
      (effects (font (size 1.27 1.27) (thickness 0.15)) (justify left bottom) hide)
    )
    (property "MPN" "CC0201KRX6S5BB104" (at 19.05 190.5 0)
      (effects (font (size 1.27 1.27) (thickness 0.15)) (justify left bottom) hide)
    )
    (property "Val" "100n" (at 36.83 174.625 90)
      (effects (font (size 1.27 1.27) (thickness 0.15)) (justify left))
    )
    (property "License" "Apache-2.0" (at 13.97 190.5 0)
      (effects (font (size 1.27 1.27) (thickness 0.15)) (justify left bottom) hide)
    )
    (property "Author" "Antmicro" (at 11.43 190.5 0)
      (effects (font (size 1.27 1.27) (thickness 0.15)) (justify left bottom) hide)
    )
    (property "Voltage" "" (at 8.89 190.5 0)
      (effects (font (size 1.27 1.27)) (justify left bottom) hide)
    )
    (property "Dielectric" "" (at 6.35 190.5 0)
      (effects (font (size 1.27 1.27)) (justify left bottom) hide)
    )
    (pin "1")
    (pin "2")
    (instances
      (project "data-center-rdimm-ddr4-tester"
        (path ""
          (reference "C276") (unit 1)
        )
      )
    )
  )

  (symbol (lib_id "antmicropower:GND") (at 269.875 116.205 0) (unit 1)
    (in_bom yes) (on_board yes) (dnp no) (fields_autoplaced)
    (property "Reference" "#PWR0339" (at 269.875 122.555 0)
      (effects (font (size 1.27 1.27)) hide)
    )
    (property "Value" "GND" (at 269.875 120.65 0)
      (effects (font (size 1.27 1.27)))
    )
    (property "Footprint" "" (at 269.875 116.205 0)
      (effects (font (size 1.27 1.27)) hide)
    )
    (property "Datasheet" "" (at 269.875 116.205 0)
      (effects (font (size 1.27 1.27)) hide)
    )
    (property "Author" "Antmicro" (at 278.765 123.825 0)
      (effects (font (size 1.27 1.27) (thickness 0.15)) (justify left bottom) hide)
    )
    (property "License" "Apache-2.0" (at 278.765 126.365 0)
      (effects (font (size 1.27 1.27) (thickness 0.15)) (justify left bottom) hide)
    )
    (pin "1")
    (instances
      (project "data-center-rdimm-ddr4-tester"
        (path ""
          (reference "#PWR0339") (unit 1)
        )
      )
    )
  )

  (symbol (lib_id "antmicroCapacitorsmisc:C_100n_0201") (at 109.22 201.295 270) (unit 1)
    (in_bom yes) (on_board yes) (dnp no)
    (property "Reference" "C94" (at 109.22 201.93 90)
      (effects (font (size 1.524 1.524)) (justify left))
    )
    (property "Value" "C_100n_0201" (at 99.06 221.615 0)
      (effects (font (size 1.27 1.27) (thickness 0.15)) (justify left bottom) hide)
    )
    (property "Footprint" "antmicro-footprints:C_0201" (at 96.52 221.615 0)
      (effects (font (size 1.27 1.27) (thickness 0.15)) (justify left bottom) hide)
    )
    (property "Datasheet" " " (at 93.98 221.615 0)
      (effects (font (size 1.27 1.27) (thickness 0.15)) (justify left bottom) hide)
    )
    (property "Manufacturer" "Yaego" (at 88.9 221.615 0)
      (effects (font (size 1.27 1.27) (thickness 0.15)) (justify left bottom) hide)
    )
    (property "MPN" "CC0201KRX6S5BB104" (at 91.44 221.615 0)
      (effects (font (size 1.27 1.27) (thickness 0.15)) (justify left bottom) hide)
    )
    (property "Val" "100n" (at 109.22 205.74 90)
      (effects (font (size 1.27 1.27) (thickness 0.15)) (justify left))
    )
    (property "License" "Apache-2.0" (at 86.36 221.615 0)
      (effects (font (size 1.27 1.27) (thickness 0.15)) (justify left bottom) hide)
    )
    (property "Author" "Antmicro" (at 83.82 221.615 0)
      (effects (font (size 1.27 1.27) (thickness 0.15)) (justify left bottom) hide)
    )
    (property "Voltage" "" (at 81.28 221.615 0)
      (effects (font (size 1.27 1.27)) (justify left bottom) hide)
    )
    (property "Dielectric" "" (at 78.74 221.615 0)
      (effects (font (size 1.27 1.27)) (justify left bottom) hide)
    )
    (pin "1")
    (pin "2")
    (instances
      (project "data-center-rdimm-ddr4-tester"
        (path ""
          (reference "C94") (unit 1)
        )
      )
    )
  )

  (symbol (lib_id "antmicroCapacitorsmisc:C_100n_0201") (at 356.235 111.125 270) (unit 1)
    (in_bom yes) (on_board yes) (dnp no)
    (property "Reference" "C253" (at 356.87 111.76 90)
      (effects (font (size 1.524 1.524)) (justify left))
    )
    (property "Value" "C_100n_0201" (at 346.075 131.445 0)
      (effects (font (size 1.27 1.27) (thickness 0.15)) (justify left bottom) hide)
    )
    (property "Footprint" "antmicro-footprints:C_0201" (at 343.535 131.445 0)
      (effects (font (size 1.27 1.27) (thickness 0.15)) (justify left bottom) hide)
    )
    (property "Datasheet" " " (at 340.995 131.445 0)
      (effects (font (size 1.27 1.27) (thickness 0.15)) (justify left bottom) hide)
    )
    (property "Manufacturer" "Yaego" (at 335.915 131.445 0)
      (effects (font (size 1.27 1.27) (thickness 0.15)) (justify left bottom) hide)
    )
    (property "MPN" "CC0201KRX6S5BB104" (at 338.455 131.445 0)
      (effects (font (size 1.27 1.27) (thickness 0.15)) (justify left bottom) hide)
    )
    (property "Val" "100n" (at 356.87 115.57 90)
      (effects (font (size 1.27 1.27) (thickness 0.15)) (justify left))
    )
    (property "License" "Apache-2.0" (at 333.375 131.445 0)
      (effects (font (size 1.27 1.27) (thickness 0.15)) (justify left bottom) hide)
    )
    (property "Author" "Antmicro" (at 330.835 131.445 0)
      (effects (font (size 1.27 1.27) (thickness 0.15)) (justify left bottom) hide)
    )
    (property "Voltage" "" (at 328.295 131.445 0)
      (effects (font (size 1.27 1.27)) (justify left bottom) hide)
    )
    (property "Dielectric" "" (at 325.755 131.445 0)
      (effects (font (size 1.27 1.27)) (justify left bottom) hide)
    )
    (pin "1")
    (pin "2")
    (instances
      (project "data-center-rdimm-ddr4-tester"
        (path ""
          (reference "C253") (unit 1)
        )
      )
    )
  )

  (symbol (lib_id "antmicropower:GND") (at 41.91 237.49 0) (unit 1)
    (in_bom yes) (on_board yes) (dnp no) (fields_autoplaced)
    (property "Reference" "#PWR0382" (at 41.91 243.84 0)
      (effects (font (size 1.27 1.27)) hide)
    )
    (property "Value" "GND" (at 41.91 241.935 0)
      (effects (font (size 1.27 1.27)))
    )
    (property "Footprint" "" (at 41.91 237.49 0)
      (effects (font (size 1.27 1.27)) hide)
    )
    (property "Datasheet" "" (at 41.91 237.49 0)
      (effects (font (size 1.27 1.27)) hide)
    )
    (property "Author" "Antmicro" (at 50.8 245.11 0)
      (effects (font (size 1.27 1.27) (thickness 0.15)) (justify left bottom) hide)
    )
    (property "License" "Apache-2.0" (at 50.8 247.65 0)
      (effects (font (size 1.27 1.27) (thickness 0.15)) (justify left bottom) hide)
    )
    (pin "1")
    (instances
      (project "data-center-rdimm-ddr4-tester"
        (path ""
          (reference "#PWR0382") (unit 1)
        )
      )
    )
  )

  (symbol (lib_id "antmicropower:GND") (at 229.87 116.205 0) (unit 1)
    (in_bom yes) (on_board yes) (dnp no) (fields_autoplaced)
    (property "Reference" "#PWR0230" (at 229.87 122.555 0)
      (effects (font (size 1.27 1.27)) hide)
    )
    (property "Value" "GND" (at 229.87 121.793 0)
      (effects (font (size 1.27 1.27)))
    )
    (property "Footprint" "" (at 229.87 116.205 0)
      (effects (font (size 1.27 1.27)) hide)
    )
    (property "Datasheet" "" (at 229.87 116.205 0)
      (effects (font (size 1.27 1.27)) hide)
    )
    (property "Author" "Antmicro" (at 238.76 123.825 0)
      (effects (font (size 1.27 1.27) (thickness 0.15)) (justify left bottom) hide)
    )
    (property "License" "Apache-2.0" (at 238.76 126.365 0)
      (effects (font (size 1.27 1.27) (thickness 0.15)) (justify left bottom) hide)
    )
    (pin "1")
    (instances
      (project "data-center-rdimm-ddr4-tester"
        (path ""
          (reference "#PWR0230") (unit 1)
        )
      )
    )
  )

  (symbol (lib_id "antmicroCapacitorsmisc:C_100n_0201") (at 334.01 111.125 270) (unit 1)
    (in_bom yes) (on_board yes) (dnp no)
    (property "Reference" "C249" (at 334.645 111.76 90)
      (effects (font (size 1.524 1.524)) (justify left))
    )
    (property "Value" "C_100n_0201" (at 323.85 131.445 0)
      (effects (font (size 1.27 1.27) (thickness 0.15)) (justify left bottom) hide)
    )
    (property "Footprint" "antmicro-footprints:C_0201" (at 321.31 131.445 0)
      (effects (font (size 1.27 1.27) (thickness 0.15)) (justify left bottom) hide)
    )
    (property "Datasheet" " " (at 318.77 131.445 0)
      (effects (font (size 1.27 1.27) (thickness 0.15)) (justify left bottom) hide)
    )
    (property "Manufacturer" "Yaego" (at 313.69 131.445 0)
      (effects (font (size 1.27 1.27) (thickness 0.15)) (justify left bottom) hide)
    )
    (property "MPN" "CC0201KRX6S5BB104" (at 316.23 131.445 0)
      (effects (font (size 1.27 1.27) (thickness 0.15)) (justify left bottom) hide)
    )
    (property "Val" "100n" (at 334.645 115.57 90)
      (effects (font (size 1.27 1.27) (thickness 0.15)) (justify left))
    )
    (property "License" "Apache-2.0" (at 311.15 131.445 0)
      (effects (font (size 1.27 1.27) (thickness 0.15)) (justify left bottom) hide)
    )
    (property "Author" "Antmicro" (at 308.61 131.445 0)
      (effects (font (size 1.27 1.27) (thickness 0.15)) (justify left bottom) hide)
    )
    (property "Voltage" "" (at 306.07 131.445 0)
      (effects (font (size 1.27 1.27)) (justify left bottom) hide)
    )
    (property "Dielectric" "" (at 303.53 131.445 0)
      (effects (font (size 1.27 1.27)) (justify left bottom) hide)
    )
    (pin "1")
    (pin "2")
    (instances
      (project "data-center-rdimm-ddr4-tester"
        (path ""
          (reference "C249") (unit 1)
        )
      )
    )
  )

  (symbol (lib_id "antmicroCapacitorsmisc:C_100n_0201") (at 81.915 232.41 270) (unit 1)
    (in_bom yes) (on_board yes) (dnp no)
    (property "Reference" "C306" (at 81.915 233.045 90)
      (effects (font (size 1.524 1.524)) (justify left))
    )
    (property "Value" "C_100n_0201" (at 71.755 252.73 0)
      (effects (font (size 1.27 1.27) (thickness 0.15)) (justify left bottom) hide)
    )
    (property "Footprint" "antmicro-footprints:C_0201" (at 69.215 252.73 0)
      (effects (font (size 1.27 1.27) (thickness 0.15)) (justify left bottom) hide)
    )
    (property "Datasheet" " " (at 66.675 252.73 0)
      (effects (font (size 1.27 1.27) (thickness 0.15)) (justify left bottom) hide)
    )
    (property "Manufacturer" "Yaego" (at 61.595 252.73 0)
      (effects (font (size 1.27 1.27) (thickness 0.15)) (justify left bottom) hide)
    )
    (property "MPN" "CC0201KRX6S5BB104" (at 64.135 252.73 0)
      (effects (font (size 1.27 1.27) (thickness 0.15)) (justify left bottom) hide)
    )
    (property "Val" "100n" (at 81.915 236.855 90)
      (effects (font (size 1.27 1.27) (thickness 0.15)) (justify left))
    )
    (property "License" "Apache-2.0" (at 59.055 252.73 0)
      (effects (font (size 1.27 1.27) (thickness 0.15)) (justify left bottom) hide)
    )
    (property "Author" "Antmicro" (at 56.515 252.73 0)
      (effects (font (size 1.27 1.27) (thickness 0.15)) (justify left bottom) hide)
    )
    (property "Voltage" "" (at 53.975 252.73 0)
      (effects (font (size 1.27 1.27)) (justify left bottom) hide)
    )
    (property "Dielectric" "" (at 51.435 252.73 0)
      (effects (font (size 1.27 1.27)) (justify left bottom) hide)
    )
    (pin "1")
    (pin "2")
    (instances
      (project "data-center-rdimm-ddr4-tester"
        (path ""
          (reference "C306") (unit 1)
        )
      )
    )
  )

  (symbol (lib_id "antmicropower:GND") (at 35.56 237.49 0) (unit 1)
    (in_bom yes) (on_board yes) (dnp no) (fields_autoplaced)
    (property "Reference" "#PWR0381" (at 35.56 243.84 0)
      (effects (font (size 1.27 1.27)) hide)
    )
    (property "Value" "GND" (at 35.56 241.935 0)
      (effects (font (size 1.27 1.27)))
    )
    (property "Footprint" "" (at 35.56 237.49 0)
      (effects (font (size 1.27 1.27)) hide)
    )
    (property "Datasheet" "" (at 35.56 237.49 0)
      (effects (font (size 1.27 1.27)) hide)
    )
    (property "Author" "Antmicro" (at 44.45 245.11 0)
      (effects (font (size 1.27 1.27) (thickness 0.15)) (justify left bottom) hide)
    )
    (property "License" "Apache-2.0" (at 44.45 247.65 0)
      (effects (font (size 1.27 1.27) (thickness 0.15)) (justify left bottom) hide)
    )
    (pin "1")
    (instances
      (project "data-center-rdimm-ddr4-tester"
        (path ""
          (reference "#PWR0381") (unit 1)
        )
      )
    )
  )

  (symbol (lib_id "antmicropower:GND") (at 78.74 175.26 0) (unit 1)
    (in_bom yes) (on_board yes) (dnp no) (fields_autoplaced)
    (property "Reference" "#PWR0377" (at 78.74 181.61 0)
      (effects (font (size 1.27 1.27)) hide)
    )
    (property "Value" "GND" (at 78.74 179.705 0)
      (effects (font (size 1.27 1.27)))
    )
    (property "Footprint" "" (at 78.74 175.26 0)
      (effects (font (size 1.27 1.27)) hide)
    )
    (property "Datasheet" "" (at 78.74 175.26 0)
      (effects (font (size 1.27 1.27)) hide)
    )
    (property "Author" "Antmicro" (at 87.63 182.88 0)
      (effects (font (size 1.27 1.27) (thickness 0.15)) (justify left bottom) hide)
    )
    (property "License" "Apache-2.0" (at 87.63 185.42 0)
      (effects (font (size 1.27 1.27) (thickness 0.15)) (justify left bottom) hide)
    )
    (pin "1")
    (instances
      (project "data-center-rdimm-ddr4-tester"
        (path ""
          (reference "#PWR0377") (unit 1)
        )
      )
    )
  )

  (symbol (lib_id "antmicropower:GND") (at 318.77 116.205 0) (unit 1)
    (in_bom yes) (on_board yes) (dnp no) (fields_autoplaced)
    (property "Reference" "#PWR0341" (at 318.77 122.555 0)
      (effects (font (size 1.27 1.27)) hide)
    )
    (property "Value" "GND" (at 318.77 120.65 0)
      (effects (font (size 1.27 1.27)))
    )
    (property "Footprint" "" (at 318.77 116.205 0)
      (effects (font (size 1.27 1.27)) hide)
    )
    (property "Datasheet" "" (at 318.77 116.205 0)
      (effects (font (size 1.27 1.27)) hide)
    )
    (property "Author" "Antmicro" (at 327.66 123.825 0)
      (effects (font (size 1.27 1.27) (thickness 0.15)) (justify left bottom) hide)
    )
    (property "License" "Apache-2.0" (at 327.66 126.365 0)
      (effects (font (size 1.27 1.27) (thickness 0.15)) (justify left bottom) hide)
    )
    (pin "1")
    (instances
      (project "data-center-rdimm-ddr4-tester"
        (path ""
          (reference "#PWR0341") (unit 1)
        )
      )
    )
  )

  (symbol (lib_id "antmicropower:GND") (at 255.27 116.205 0) (unit 1)
    (in_bom yes) (on_board yes) (dnp no) (fields_autoplaced)
    (property "Reference" "#PWR0342" (at 255.27 122.555 0)
      (effects (font (size 1.27 1.27)) hide)
    )
    (property "Value" "GND" (at 255.27 120.65 0)
      (effects (font (size 1.27 1.27)))
    )
    (property "Footprint" "" (at 255.27 116.205 0)
      (effects (font (size 1.27 1.27)) hide)
    )
    (property "Datasheet" "" (at 255.27 116.205 0)
      (effects (font (size 1.27 1.27)) hide)
    )
    (property "Author" "Antmicro" (at 264.16 123.825 0)
      (effects (font (size 1.27 1.27) (thickness 0.15)) (justify left bottom) hide)
    )
    (property "License" "Apache-2.0" (at 264.16 126.365 0)
      (effects (font (size 1.27 1.27) (thickness 0.15)) (justify left bottom) hide)
    )
    (pin "1")
    (instances
      (project "data-center-rdimm-ddr4-tester"
        (path ""
          (reference "#PWR0342") (unit 1)
        )
      )
    )
  )

  (symbol (lib_id "antmicropower:GND") (at 102.235 237.49 0) (unit 1)
    (in_bom yes) (on_board yes) (dnp no) (fields_autoplaced)
    (property "Reference" "#PWR0384" (at 102.235 243.84 0)
      (effects (font (size 1.27 1.27)) hide)
    )
    (property "Value" "GND" (at 102.235 241.935 0)
      (effects (font (size 1.27 1.27)))
    )
    (property "Footprint" "" (at 102.235 237.49 0)
      (effects (font (size 1.27 1.27)) hide)
    )
    (property "Datasheet" "" (at 102.235 237.49 0)
      (effects (font (size 1.27 1.27)) hide)
    )
    (property "Author" "Antmicro" (at 111.125 245.11 0)
      (effects (font (size 1.27 1.27) (thickness 0.15)) (justify left bottom) hide)
    )
    (property "License" "Apache-2.0" (at 111.125 247.65 0)
      (effects (font (size 1.27 1.27) (thickness 0.15)) (justify left bottom) hide)
    )
    (pin "1")
    (instances
      (project "data-center-rdimm-ddr4-tester"
        (path ""
          (reference "#PWR0384") (unit 1)
        )
      )
    )
  )

  (symbol (lib_id "antmicropower:GND") (at 36.83 175.26 0) (unit 1)
    (in_bom yes) (on_board yes) (dnp no) (fields_autoplaced)
    (property "Reference" "#PWR0368" (at 36.83 181.61 0)
      (effects (font (size 1.27 1.27)) hide)
    )
    (property "Value" "GND" (at 36.83 180.34 0)
      (effects (font (size 1.27 1.27)))
    )
    (property "Footprint" "" (at 36.83 175.26 0)
      (effects (font (size 1.27 1.27)) hide)
    )
    (property "Datasheet" "" (at 36.83 175.26 0)
      (effects (font (size 1.27 1.27)) hide)
    )
    (property "Author" "Antmicro" (at 45.72 182.88 0)
      (effects (font (size 1.27 1.27) (thickness 0.15)) (justify left bottom) hide)
    )
    (property "License" "Apache-2.0" (at 45.72 185.42 0)
      (effects (font (size 1.27 1.27) (thickness 0.15)) (justify left bottom) hide)
    )
    (pin "1")
    (instances
      (project "data-center-rdimm-ddr4-tester"
        (path ""
          (reference "#PWR0368") (unit 1)
        )
      )
    )
  )

  (symbol (lib_id "antmicroCapacitorsmisc:C_100n_0201") (at 88.9 232.41 270) (unit 1)
    (in_bom yes) (on_board yes) (dnp no)
    (property "Reference" "C307" (at 88.9 233.045 90)
      (effects (font (size 1.524 1.524)) (justify left))
    )
    (property "Value" "C_100n_0201" (at 78.74 252.73 0)
      (effects (font (size 1.27 1.27) (thickness 0.15)) (justify left bottom) hide)
    )
    (property "Footprint" "antmicro-footprints:C_0201" (at 76.2 252.73 0)
      (effects (font (size 1.27 1.27) (thickness 0.15)) (justify left bottom) hide)
    )
    (property "Datasheet" " " (at 73.66 252.73 0)
      (effects (font (size 1.27 1.27) (thickness 0.15)) (justify left bottom) hide)
    )
    (property "Manufacturer" "Yaego" (at 68.58 252.73 0)
      (effects (font (size 1.27 1.27) (thickness 0.15)) (justify left bottom) hide)
    )
    (property "MPN" "CC0201KRX6S5BB104" (at 71.12 252.73 0)
      (effects (font (size 1.27 1.27) (thickness 0.15)) (justify left bottom) hide)
    )
    (property "Val" "100n" (at 88.9 236.855 90)
      (effects (font (size 1.27 1.27) (thickness 0.15)) (justify left))
    )
    (property "License" "Apache-2.0" (at 66.04 252.73 0)
      (effects (font (size 1.27 1.27) (thickness 0.15)) (justify left bottom) hide)
    )
    (property "Author" "Antmicro" (at 63.5 252.73 0)
      (effects (font (size 1.27 1.27) (thickness 0.15)) (justify left bottom) hide)
    )
    (property "Voltage" "" (at 60.96 252.73 0)
      (effects (font (size 1.27 1.27)) (justify left bottom) hide)
    )
    (property "Dielectric" "" (at 58.42 252.73 0)
      (effects (font (size 1.27 1.27)) (justify left bottom) hide)
    )
    (pin "1")
    (pin "2")
    (instances
      (project "data-center-rdimm-ddr4-tester"
        (path ""
          (reference "C307") (unit 1)
        )
      )
    )
  )

  (symbol (lib_id "antmicroCapacitorsmisc:C_100n_0201") (at 277.495 111.125 270) (unit 1)
    (in_bom yes) (on_board yes) (dnp no)
    (property "Reference" "C243" (at 278.13 111.76 90)
      (effects (font (size 1.524 1.524)) (justify left))
    )
    (property "Value" "C_100n_0201" (at 267.335 131.445 0)
      (effects (font (size 1.27 1.27) (thickness 0.15)) (justify left bottom) hide)
    )
    (property "Footprint" "antmicro-footprints:C_0201" (at 264.795 131.445 0)
      (effects (font (size 1.27 1.27) (thickness 0.15)) (justify left bottom) hide)
    )
    (property "Datasheet" " " (at 262.255 131.445 0)
      (effects (font (size 1.27 1.27) (thickness 0.15)) (justify left bottom) hide)
    )
    (property "Manufacturer" "Yaego" (at 257.175 131.445 0)
      (effects (font (size 1.27 1.27) (thickness 0.15)) (justify left bottom) hide)
    )
    (property "MPN" "CC0201KRX6S5BB104" (at 259.715 131.445 0)
      (effects (font (size 1.27 1.27) (thickness 0.15)) (justify left bottom) hide)
    )
    (property "Val" "100n" (at 278.13 115.57 90)
      (effects (font (size 1.27 1.27) (thickness 0.15)) (justify left))
    )
    (property "License" "Apache-2.0" (at 254.635 131.445 0)
      (effects (font (size 1.27 1.27) (thickness 0.15)) (justify left bottom) hide)
    )
    (property "Author" "Antmicro" (at 252.095 131.445 0)
      (effects (font (size 1.27 1.27) (thickness 0.15)) (justify left bottom) hide)
    )
    (property "Voltage" "" (at 249.555 131.445 0)
      (effects (font (size 1.27 1.27)) (justify left bottom) hide)
    )
    (property "Dielectric" "" (at 247.015 131.445 0)
      (effects (font (size 1.27 1.27)) (justify left bottom) hide)
    )
    (pin "1")
    (pin "2")
    (instances
      (project "data-center-rdimm-ddr4-tester"
        (path ""
          (reference "C243") (unit 1)
        )
      )
    )
  )

  (symbol (lib_id "antmicropower:GND") (at 88.9 237.49 0) (unit 1)
    (in_bom yes) (on_board yes) (dnp no) (fields_autoplaced)
    (property "Reference" "#PWR0389" (at 88.9 243.84 0)
      (effects (font (size 1.27 1.27)) hide)
    )
    (property "Value" "GND" (at 88.9 241.935 0)
      (effects (font (size 1.27 1.27)))
    )
    (property "Footprint" "" (at 88.9 237.49 0)
      (effects (font (size 1.27 1.27)) hide)
    )
    (property "Datasheet" "" (at 88.9 237.49 0)
      (effects (font (size 1.27 1.27)) hide)
    )
    (property "Author" "Antmicro" (at 97.79 245.11 0)
      (effects (font (size 1.27 1.27) (thickness 0.15)) (justify left bottom) hide)
    )
    (property "License" "Apache-2.0" (at 97.79 247.65 0)
      (effects (font (size 1.27 1.27) (thickness 0.15)) (justify left bottom) hide)
    )
    (pin "1")
    (instances
      (project "data-center-rdimm-ddr4-tester"
        (path ""
          (reference "#PWR0389") (unit 1)
        )
      )
    )
  )

  (symbol (lib_id "antmicroCapacitorsmisc:C_100n_0201") (at 82.55 201.295 270) (unit 1)
    (in_bom yes) (on_board yes) (dnp no)
    (property "Reference" "C90" (at 82.55 201.93 90)
      (effects (font (size 1.524 1.524)) (justify left))
    )
    (property "Value" "C_100n_0201" (at 72.39 221.615 0)
      (effects (font (size 1.27 1.27) (thickness 0.15)) (justify left bottom) hide)
    )
    (property "Footprint" "antmicro-footprints:C_0201" (at 69.85 221.615 0)
      (effects (font (size 1.27 1.27) (thickness 0.15)) (justify left bottom) hide)
    )
    (property "Datasheet" " " (at 67.31 221.615 0)
      (effects (font (size 1.27 1.27) (thickness 0.15)) (justify left bottom) hide)
    )
    (property "Manufacturer" "Yaego" (at 62.23 221.615 0)
      (effects (font (size 1.27 1.27) (thickness 0.15)) (justify left bottom) hide)
    )
    (property "MPN" "CC0201KRX6S5BB104" (at 64.77 221.615 0)
      (effects (font (size 1.27 1.27) (thickness 0.15)) (justify left bottom) hide)
    )
    (property "Val" "100n" (at 82.55 205.74 90)
      (effects (font (size 1.27 1.27) (thickness 0.15)) (justify left))
    )
    (property "License" "Apache-2.0" (at 59.69 221.615 0)
      (effects (font (size 1.27 1.27) (thickness 0.15)) (justify left bottom) hide)
    )
    (property "Author" "Antmicro" (at 57.15 221.615 0)
      (effects (font (size 1.27 1.27) (thickness 0.15)) (justify left bottom) hide)
    )
    (property "Voltage" "" (at 54.61 221.615 0)
      (effects (font (size 1.27 1.27)) (justify left bottom) hide)
    )
    (property "Dielectric" "" (at 52.07 221.615 0)
      (effects (font (size 1.27 1.27)) (justify left bottom) hide)
    )
    (pin "1")
    (pin "2")
    (instances
      (project "data-center-rdimm-ddr4-tester"
        (path ""
          (reference "C90") (unit 1)
        )
      )
    )
  )

  (symbol (lib_id "antmicroCapacitors0603:C_47u_0603") (at 29.21 201.295 270) (unit 1)
    (in_bom yes) (on_board yes) (dnp no)
    (property "Reference" "C78" (at 29.21 201.93 90)
      (effects (font (size 1.524 1.524)) (justify left))
    )
    (property "Value" "C_47u_0603" (at 19.05 221.615 0)
      (effects (font (size 1.27 1.27) (thickness 0.15)) (justify left bottom) hide)
    )
    (property "Footprint" "antmicro-footprints:C_0603_1608Metric" (at 16.51 221.615 0)
      (effects (font (size 1.27 1.27) (thickness 0.15)) (justify left bottom) hide)
    )
    (property "Datasheet" " " (at 13.97 221.615 0)
      (effects (font (size 1.27 1.27) (thickness 0.15)) (justify left bottom) hide)
    )
    (property "Manufacturer" "Murata" (at 8.89 221.615 0)
      (effects (font (size 1.27 1.27) (thickness 0.15)) (justify left bottom) hide)
    )
    (property "MPN" "GRM188R60J476ME15D" (at 11.43 221.615 0)
      (effects (font (size 1.27 1.27) (thickness 0.15)) (justify left bottom) hide)
    )
    (property "Val" "47u" (at 29.21 205.74 90)
      (effects (font (size 1.27 1.27) (thickness 0.15)) (justify left))
    )
    (property "License" "Apache-2.0" (at 6.35 221.615 0)
      (effects (font (size 1.27 1.27) (thickness 0.15)) (justify left bottom) hide)
    )
    (property "Author" "Antmicro" (at 3.81 221.615 0)
      (effects (font (size 1.27 1.27) (thickness 0.15)) (justify left bottom) hide)
    )
    (property "Voltage" "" (at 1.27 221.615 0)
      (effects (font (size 1.27 1.27)) (justify left bottom) hide)
    )
    (property "Dielectric" "" (at -1.27 221.615 0)
      (effects (font (size 1.27 1.27)) (justify left bottom) hide)
    )
    (pin "1")
    (pin "2")
    (instances
      (project "data-center-rdimm-ddr4-tester"
        (path ""
          (reference "C78") (unit 1)
        )
      )
    )
  )

  (symbol (lib_id "antmicroCapacitorsmisc:C_100n_0201") (at 92.71 170.18 270) (unit 1)
    (in_bom yes) (on_board yes) (dnp no)
    (property "Reference" "C297" (at 92.71 170.815 90)
      (effects (font (size 1.524 1.524)) (justify left))
    )
    (property "Value" "C_100n_0201" (at 82.55 190.5 0)
      (effects (font (size 1.27 1.27) (thickness 0.15)) (justify left bottom) hide)
    )
    (property "Footprint" "antmicro-footprints:C_0201" (at 80.01 190.5 0)
      (effects (font (size 1.27 1.27) (thickness 0.15)) (justify left bottom) hide)
    )
    (property "Datasheet" " " (at 77.47 190.5 0)
      (effects (font (size 1.27 1.27) (thickness 0.15)) (justify left bottom) hide)
    )
    (property "Manufacturer" "Yaego" (at 72.39 190.5 0)
      (effects (font (size 1.27 1.27) (thickness 0.15)) (justify left bottom) hide)
    )
    (property "MPN" "CC0201KRX6S5BB104" (at 74.93 190.5 0)
      (effects (font (size 1.27 1.27) (thickness 0.15)) (justify left bottom) hide)
    )
    (property "Val" "100n" (at 92.71 174.625 90)
      (effects (font (size 1.27 1.27) (thickness 0.15)) (justify left))
    )
    (property "License" "Apache-2.0" (at 69.85 190.5 0)
      (effects (font (size 1.27 1.27) (thickness 0.15)) (justify left bottom) hide)
    )
    (property "Author" "Antmicro" (at 67.31 190.5 0)
      (effects (font (size 1.27 1.27) (thickness 0.15)) (justify left bottom) hide)
    )
    (property "Voltage" "" (at 64.77 190.5 0)
      (effects (font (size 1.27 1.27)) (justify left bottom) hide)
    )
    (property "Dielectric" "" (at 62.23 190.5 0)
      (effects (font (size 1.27 1.27)) (justify left bottom) hide)
    )
    (pin "1")
    (pin "2")
    (instances
      (project "data-center-rdimm-ddr4-tester"
        (path ""
          (reference "C297") (unit 1)
        )
      )
    )
  )

  (symbol (lib_id "antmicroCapacitorsmisc:C_100n_0201") (at 55.88 201.295 270) (unit 1)
    (in_bom yes) (on_board yes) (dnp no)
    (property "Reference" "C86" (at 55.88 201.93 90)
      (effects (font (size 1.524 1.524)) (justify left))
    )
    (property "Value" "C_100n_0201" (at 45.72 221.615 0)
      (effects (font (size 1.27 1.27) (thickness 0.15)) (justify left bottom) hide)
    )
    (property "Footprint" "antmicro-footprints:C_0201" (at 43.18 221.615 0)
      (effects (font (size 1.27 1.27) (thickness 0.15)) (justify left bottom) hide)
    )
    (property "Datasheet" " " (at 40.64 221.615 0)
      (effects (font (size 1.27 1.27) (thickness 0.15)) (justify left bottom) hide)
    )
    (property "Manufacturer" "Yaego" (at 35.56 221.615 0)
      (effects (font (size 1.27 1.27) (thickness 0.15)) (justify left bottom) hide)
    )
    (property "MPN" "CC0201KRX6S5BB104" (at 38.1 221.615 0)
      (effects (font (size 1.27 1.27) (thickness 0.15)) (justify left bottom) hide)
    )
    (property "Val" "100n" (at 55.88 205.74 90)
      (effects (font (size 1.27 1.27) (thickness 0.15)) (justify left))
    )
    (property "License" "Apache-2.0" (at 33.02 221.615 0)
      (effects (font (size 1.27 1.27) (thickness 0.15)) (justify left bottom) hide)
    )
    (property "Author" "Antmicro" (at 30.48 221.615 0)
      (effects (font (size 1.27 1.27) (thickness 0.15)) (justify left bottom) hide)
    )
    (property "Voltage" "" (at 27.94 221.615 0)
      (effects (font (size 1.27 1.27)) (justify left bottom) hide)
    )
    (property "Dielectric" "" (at 25.4 221.615 0)
      (effects (font (size 1.27 1.27)) (justify left bottom) hide)
    )
    (pin "1")
    (pin "2")
    (instances
      (project "data-center-rdimm-ddr4-tester"
        (path ""
          (reference "C86") (unit 1)
        )
      )
    )
  )

  (symbol (lib_id "antmicropower:GND") (at 349.25 116.205 0) (unit 1)
    (in_bom yes) (on_board yes) (dnp no) (fields_autoplaced)
    (property "Reference" "#PWR0148" (at 349.25 122.555 0)
      (effects (font (size 1.27 1.27)) hide)
    )
    (property "Value" "GND" (at 349.25 120.65 0)
      (effects (font (size 1.27 1.27)))
    )
    (property "Footprint" "" (at 349.25 116.205 0)
      (effects (font (size 1.27 1.27)) hide)
    )
    (property "Datasheet" "" (at 349.25 116.205 0)
      (effects (font (size 1.27 1.27)) hide)
    )
    (property "Author" "Antmicro" (at 358.14 123.825 0)
      (effects (font (size 1.27 1.27) (thickness 0.15)) (justify left bottom) hide)
    )
    (property "License" "Apache-2.0" (at 358.14 126.365 0)
      (effects (font (size 1.27 1.27) (thickness 0.15)) (justify left bottom) hide)
    )
    (pin "1")
    (instances
      (project "data-center-rdimm-ddr4-tester"
        (path ""
          (reference "#PWR0148") (unit 1)
        )
      )
    )
  )

  (symbol (lib_id "antmicroCapacitors0402:C_4u7_0402") (at 379.095 111.125 270) (unit 1)
    (in_bom yes) (on_board yes) (dnp no)
    (property "Reference" "C256" (at 379.73 111.76 90)
      (effects (font (size 1.524 1.524)) (justify left))
    )
    (property "Value" "C_4u7_0402" (at 368.935 131.445 0)
      (effects (font (size 1.27 1.27) (thickness 0.15)) (justify left bottom) hide)
    )
    (property "Footprint" "antmicro-footprints:C_0402_1005Metric" (at 366.395 131.445 0)
      (effects (font (size 1.27 1.27) (thickness 0.15)) (justify left bottom) hide)
    )
    (property "Datasheet" " " (at 363.855 131.445 0)
      (effects (font (size 1.27 1.27) (thickness 0.15)) (justify left bottom) hide)
    )
    (property "Manufacturer" "Murata" (at 358.775 131.445 0)
      (effects (font (size 1.27 1.27) (thickness 0.15)) (justify left bottom) hide)
    )
    (property "MPN" "GRM155R61A475MEAAD" (at 361.315 131.445 0)
      (effects (font (size 1.27 1.27) (thickness 0.15)) (justify left bottom) hide)
    )
    (property "Val" "4u7" (at 379.73 115.57 90)
      (effects (font (size 1.27 1.27) (thickness 0.15)) (justify left))
    )
    (property "License" "Apache-2.0" (at 356.235 131.445 0)
      (effects (font (size 1.27 1.27) (thickness 0.15)) (justify left bottom) hide)
    )
    (property "Author" "Antmicro" (at 353.695 131.445 0)
      (effects (font (size 1.27 1.27) (thickness 0.15)) (justify left bottom) hide)
    )
    (property "Voltage" "" (at 351.155 131.445 0)
      (effects (font (size 1.27 1.27)) (justify left bottom) hide)
    )
    (property "Dielectric" "" (at 348.615 131.445 0)
      (effects (font (size 1.27 1.27)) (justify left bottom) hide)
    )
    (pin "1")
    (pin "2")
    (instances
      (project "data-center-rdimm-ddr4-tester"
        (path ""
          (reference "C256") (unit 1)
        )
      )
    )
  )

  (symbol (lib_id "antmicropower:GND") (at 57.785 175.26 0) (unit 1)
    (in_bom yes) (on_board yes) (dnp no) (fields_autoplaced)
    (property "Reference" "#PWR0361" (at 57.785 181.61 0)
      (effects (font (size 1.27 1.27)) hide)
    )
    (property "Value" "GND" (at 57.785 179.705 0)
      (effects (font (size 1.27 1.27)))
    )
    (property "Footprint" "" (at 57.785 175.26 0)
      (effects (font (size 1.27 1.27)) hide)
    )
    (property "Datasheet" "" (at 57.785 175.26 0)
      (effects (font (size 1.27 1.27)) hide)
    )
    (property "Author" "Antmicro" (at 66.675 182.88 0)
      (effects (font (size 1.27 1.27) (thickness 0.15)) (justify left bottom) hide)
    )
    (property "License" "Apache-2.0" (at 66.675 185.42 0)
      (effects (font (size 1.27 1.27) (thickness 0.15)) (justify left bottom) hide)
    )
    (pin "1")
    (instances
      (project "data-center-rdimm-ddr4-tester"
        (path ""
          (reference "#PWR0361") (unit 1)
        )
      )
    )
  )

  (symbol (lib_id "antmicropower:GND") (at 43.815 175.26 0) (unit 1)
    (in_bom yes) (on_board yes) (dnp no) (fields_autoplaced)
    (property "Reference" "#PWR0366" (at 43.815 181.61 0)
      (effects (font (size 1.27 1.27)) hide)
    )
    (property "Value" "GND" (at 43.815 180.34 0)
      (effects (font (size 1.27 1.27)))
    )
    (property "Footprint" "" (at 43.815 175.26 0)
      (effects (font (size 1.27 1.27)) hide)
    )
    (property "Datasheet" "" (at 43.815 175.26 0)
      (effects (font (size 1.27 1.27)) hide)
    )
    (property "Author" "Antmicro" (at 52.705 182.88 0)
      (effects (font (size 1.27 1.27) (thickness 0.15)) (justify left bottom) hide)
    )
    (property "License" "Apache-2.0" (at 52.705 185.42 0)
      (effects (font (size 1.27 1.27) (thickness 0.15)) (justify left bottom) hide)
    )
    (pin "1")
    (instances
      (project "data-center-rdimm-ddr4-tester"
        (path ""
          (reference "#PWR0366") (unit 1)
        )
      )
    )
  )

  (symbol (lib_id "antmicropower:GND") (at 334.01 116.205 0) (unit 1)
    (in_bom yes) (on_board yes) (dnp no) (fields_autoplaced)
    (property "Reference" "#PWR0204" (at 334.01 122.555 0)
      (effects (font (size 1.27 1.27)) hide)
    )
    (property "Value" "GND" (at 334.01 120.65 0)
      (effects (font (size 1.27 1.27)))
    )
    (property "Footprint" "" (at 334.01 116.205 0)
      (effects (font (size 1.27 1.27)) hide)
    )
    (property "Datasheet" "" (at 334.01 116.205 0)
      (effects (font (size 1.27 1.27)) hide)
    )
    (property "Author" "Antmicro" (at 342.9 123.825 0)
      (effects (font (size 1.27 1.27) (thickness 0.15)) (justify left bottom) hide)
    )
    (property "License" "Apache-2.0" (at 342.9 126.365 0)
      (effects (font (size 1.27 1.27) (thickness 0.15)) (justify left bottom) hide)
    )
    (pin "1")
    (instances
      (project "data-center-rdimm-ddr4-tester"
        (path ""
          (reference "#PWR0204") (unit 1)
        )
      )
    )
  )

  (symbol (lib_id "antmicropower:GND") (at 28.575 237.49 0) (unit 1)
    (in_bom yes) (on_board yes) (dnp no) (fields_autoplaced)
    (property "Reference" "#PWR0380" (at 28.575 243.84 0)
      (effects (font (size 1.27 1.27)) hide)
    )
    (property "Value" "GND" (at 28.575 241.935 0)
      (effects (font (size 1.27 1.27)))
    )
    (property "Footprint" "" (at 28.575 237.49 0)
      (effects (font (size 1.27 1.27)) hide)
    )
    (property "Datasheet" "" (at 28.575 237.49 0)
      (effects (font (size 1.27 1.27)) hide)
    )
    (property "Author" "Antmicro" (at 37.465 245.11 0)
      (effects (font (size 1.27 1.27) (thickness 0.15)) (justify left bottom) hide)
    )
    (property "License" "Apache-2.0" (at 37.465 247.65 0)
      (effects (font (size 1.27 1.27) (thickness 0.15)) (justify left bottom) hide)
    )
    (pin "1")
    (instances
      (project "data-center-rdimm-ddr4-tester"
        (path ""
          (reference "#PWR0380") (unit 1)
        )
      )
    )
  )

  (symbol (lib_id "antmicroCapacitorsmisc:C_100n_0201") (at 41.91 232.41 270) (unit 1)
    (in_bom yes) (on_board yes) (dnp no)
    (property "Reference" "C84" (at 41.91 233.045 90)
      (effects (font (size 1.524 1.524)) (justify left))
    )
    (property "Value" "C_100n_0201" (at 31.75 252.73 0)
      (effects (font (size 1.27 1.27) (thickness 0.15)) (justify left bottom) hide)
    )
    (property "Footprint" "antmicro-footprints:C_0201" (at 29.21 252.73 0)
      (effects (font (size 1.27 1.27) (thickness 0.15)) (justify left bottom) hide)
    )
    (property "Datasheet" " " (at 26.67 252.73 0)
      (effects (font (size 1.27 1.27) (thickness 0.15)) (justify left bottom) hide)
    )
    (property "Manufacturer" "Yaego" (at 21.59 252.73 0)
      (effects (font (size 1.27 1.27) (thickness 0.15)) (justify left bottom) hide)
    )
    (property "MPN" "CC0201KRX6S5BB104" (at 24.13 252.73 0)
      (effects (font (size 1.27 1.27) (thickness 0.15)) (justify left bottom) hide)
    )
    (property "Val" "100n" (at 41.91 236.855 90)
      (effects (font (size 1.27 1.27) (thickness 0.15)) (justify left))
    )
    (property "License" "Apache-2.0" (at 19.05 252.73 0)
      (effects (font (size 1.27 1.27) (thickness 0.15)) (justify left bottom) hide)
    )
    (property "Author" "Antmicro" (at 16.51 252.73 0)
      (effects (font (size 1.27 1.27) (thickness 0.15)) (justify left bottom) hide)
    )
    (property "Voltage" "" (at 13.97 252.73 0)
      (effects (font (size 1.27 1.27)) (justify left bottom) hide)
    )
    (property "Dielectric" "" (at 11.43 252.73 0)
      (effects (font (size 1.27 1.27)) (justify left bottom) hide)
    )
    (pin "1")
    (pin "2")
    (instances
      (project "data-center-rdimm-ddr4-tester"
        (path ""
          (reference "C84") (unit 1)
        )
      )
    )
  )

  (symbol (lib_id "antmicroCapacitorsmisc:C_100n_0201") (at 269.875 111.125 270) (unit 1)
    (in_bom yes) (on_board yes) (dnp no)
    (property "Reference" "C242" (at 270.51 111.76 90)
      (effects (font (size 1.524 1.524)) (justify left))
    )
    (property "Value" "C_100n_0201" (at 259.715 131.445 0)
      (effects (font (size 1.27 1.27) (thickness 0.15)) (justify left bottom) hide)
    )
    (property "Footprint" "antmicro-footprints:C_0201" (at 257.175 131.445 0)
      (effects (font (size 1.27 1.27) (thickness 0.15)) (justify left bottom) hide)
    )
    (property "Datasheet" " " (at 254.635 131.445 0)
      (effects (font (size 1.27 1.27) (thickness 0.15)) (justify left bottom) hide)
    )
    (property "Manufacturer" "Yaego" (at 249.555 131.445 0)
      (effects (font (size 1.27 1.27) (thickness 0.15)) (justify left bottom) hide)
    )
    (property "MPN" "CC0201KRX6S5BB104" (at 252.095 131.445 0)
      (effects (font (size 1.27 1.27) (thickness 0.15)) (justify left bottom) hide)
    )
    (property "Val" "100n" (at 270.51 115.57 90)
      (effects (font (size 1.27 1.27) (thickness 0.15)) (justify left))
    )
    (property "License" "Apache-2.0" (at 247.015 131.445 0)
      (effects (font (size 1.27 1.27) (thickness 0.15)) (justify left bottom) hide)
    )
    (property "Author" "Antmicro" (at 244.475 131.445 0)
      (effects (font (size 1.27 1.27) (thickness 0.15)) (justify left bottom) hide)
    )
    (property "Voltage" "" (at 241.935 131.445 0)
      (effects (font (size 1.27 1.27)) (justify left bottom) hide)
    )
    (property "Dielectric" "" (at 239.395 131.445 0)
      (effects (font (size 1.27 1.27)) (justify left bottom) hide)
    )
    (pin "1")
    (pin "2")
    (instances
      (project "data-center-rdimm-ddr4-tester"
        (path ""
          (reference "C242") (unit 1)
        )
      )
    )
  )

  (symbol (lib_id "antmicroCapacitorsmisc:C_100n_0201") (at 71.755 170.18 270) (unit 1)
    (in_bom yes) (on_board yes) (dnp no)
    (property "Reference" "C294" (at 71.755 170.815 90)
      (effects (font (size 1.524 1.524)) (justify left))
    )
    (property "Value" "C_100n_0201" (at 61.595 190.5 0)
      (effects (font (size 1.27 1.27) (thickness 0.15)) (justify left bottom) hide)
    )
    (property "Footprint" "antmicro-footprints:C_0201" (at 59.055 190.5 0)
      (effects (font (size 1.27 1.27) (thickness 0.15)) (justify left bottom) hide)
    )
    (property "Datasheet" " " (at 56.515 190.5 0)
      (effects (font (size 1.27 1.27) (thickness 0.15)) (justify left bottom) hide)
    )
    (property "Manufacturer" "Yaego" (at 51.435 190.5 0)
      (effects (font (size 1.27 1.27) (thickness 0.15)) (justify left bottom) hide)
    )
    (property "MPN" "CC0201KRX6S5BB104" (at 53.975 190.5 0)
      (effects (font (size 1.27 1.27) (thickness 0.15)) (justify left bottom) hide)
    )
    (property "Val" "100n" (at 71.755 174.625 90)
      (effects (font (size 1.27 1.27) (thickness 0.15)) (justify left))
    )
    (property "License" "Apache-2.0" (at 48.895 190.5 0)
      (effects (font (size 1.27 1.27) (thickness 0.15)) (justify left bottom) hide)
    )
    (property "Author" "Antmicro" (at 46.355 190.5 0)
      (effects (font (size 1.27 1.27) (thickness 0.15)) (justify left bottom) hide)
    )
    (property "Voltage" "" (at 43.815 190.5 0)
      (effects (font (size 1.27 1.27)) (justify left bottom) hide)
    )
    (property "Dielectric" "" (at 41.275 190.5 0)
      (effects (font (size 1.27 1.27)) (justify left bottom) hide)
    )
    (pin "1")
    (pin "2")
    (instances
      (project "data-center-rdimm-ddr4-tester"
        (path ""
          (reference "C294") (unit 1)
        )
      )
    )
  )

  (symbol (lib_id "antmicroCapacitorsmisc:C_100n_0201") (at 116.205 201.295 270) (unit 1)
    (in_bom yes) (on_board yes) (dnp no)
    (property "Reference" "C95" (at 116.205 201.93 90)
      (effects (font (size 1.524 1.524)) (justify left))
    )
    (property "Value" "C_100n_0201" (at 106.045 221.615 0)
      (effects (font (size 1.27 1.27) (thickness 0.15)) (justify left bottom) hide)
    )
    (property "Footprint" "antmicro-footprints:C_0201" (at 103.505 221.615 0)
      (effects (font (size 1.27 1.27) (thickness 0.15)) (justify left bottom) hide)
    )
    (property "Datasheet" " " (at 100.965 221.615 0)
      (effects (font (size 1.27 1.27) (thickness 0.15)) (justify left bottom) hide)
    )
    (property "Manufacturer" "Yaego" (at 95.885 221.615 0)
      (effects (font (size 1.27 1.27) (thickness 0.15)) (justify left bottom) hide)
    )
    (property "MPN" "CC0201KRX6S5BB104" (at 98.425 221.615 0)
      (effects (font (size 1.27 1.27) (thickness 0.15)) (justify left bottom) hide)
    )
    (property "Val" "100n" (at 116.205 205.74 90)
      (effects (font (size 1.27 1.27) (thickness 0.15)) (justify left))
    )
    (property "License" "Apache-2.0" (at 93.345 221.615 0)
      (effects (font (size 1.27 1.27) (thickness 0.15)) (justify left bottom) hide)
    )
    (property "Author" "Antmicro" (at 90.805 221.615 0)
      (effects (font (size 1.27 1.27) (thickness 0.15)) (justify left bottom) hide)
    )
    (property "Voltage" "" (at 88.265 221.615 0)
      (effects (font (size 1.27 1.27)) (justify left bottom) hide)
    )
    (property "Dielectric" "" (at 85.725 221.615 0)
      (effects (font (size 1.27 1.27)) (justify left bottom) hide)
    )
    (pin "1")
    (pin "2")
    (instances
      (project "data-center-rdimm-ddr4-tester"
        (path ""
          (reference "C95") (unit 1)
        )
      )
    )
  )

  (symbol (lib_id "antmicropower:GND") (at 326.39 116.205 0) (unit 1)
    (in_bom yes) (on_board yes) (dnp no) (fields_autoplaced)
    (property "Reference" "#PWR0212" (at 326.39 122.555 0)
      (effects (font (size 1.27 1.27)) hide)
    )
    (property "Value" "GND" (at 326.39 120.65 0)
      (effects (font (size 1.27 1.27)))
    )
    (property "Footprint" "" (at 326.39 116.205 0)
      (effects (font (size 1.27 1.27)) hide)
    )
    (property "Datasheet" "" (at 326.39 116.205 0)
      (effects (font (size 1.27 1.27)) hide)
    )
    (property "Author" "Antmicro" (at 335.28 123.825 0)
      (effects (font (size 1.27 1.27) (thickness 0.15)) (justify left bottom) hide)
    )
    (property "License" "Apache-2.0" (at 335.28 126.365 0)
      (effects (font (size 1.27 1.27) (thickness 0.15)) (justify left bottom) hide)
    )
    (pin "1")
    (instances
      (project "data-center-rdimm-ddr4-tester"
        (path ""
          (reference "#PWR0212") (unit 1)
        )
      )
    )
  )

  (symbol (lib_id "antmicropower:GND") (at 62.23 237.49 0) (unit 1)
    (in_bom yes) (on_board yes) (dnp no) (fields_autoplaced)
    (property "Reference" "#PWR0383" (at 62.23 243.84 0)
      (effects (font (size 1.27 1.27)) hide)
    )
    (property "Value" "GND" (at 62.23 241.935 0)
      (effects (font (size 1.27 1.27)))
    )
    (property "Footprint" "" (at 62.23 237.49 0)
      (effects (font (size 1.27 1.27)) hide)
    )
    (property "Datasheet" "" (at 62.23 237.49 0)
      (effects (font (size 1.27 1.27)) hide)
    )
    (property "Author" "Antmicro" (at 71.12 245.11 0)
      (effects (font (size 1.27 1.27) (thickness 0.15)) (justify left bottom) hide)
    )
    (property "License" "Apache-2.0" (at 71.12 247.65 0)
      (effects (font (size 1.27 1.27) (thickness 0.15)) (justify left bottom) hide)
    )
    (pin "1")
    (instances
      (project "data-center-rdimm-ddr4-tester"
        (path ""
          (reference "#PWR0383") (unit 1)
        )
      )
    )
  )

  (symbol (lib_id "antmicropower:GND") (at 50.8 175.26 0) (unit 1)
    (in_bom yes) (on_board yes) (dnp no) (fields_autoplaced)
    (property "Reference" "#PWR0362" (at 50.8 181.61 0)
      (effects (font (size 1.27 1.27)) hide)
    )
    (property "Value" "GND" (at 50.8 179.705 0)
      (effects (font (size 1.27 1.27)))
    )
    (property "Footprint" "" (at 50.8 175.26 0)
      (effects (font (size 1.27 1.27)) hide)
    )
    (property "Datasheet" "" (at 50.8 175.26 0)
      (effects (font (size 1.27 1.27)) hide)
    )
    (property "Author" "Antmicro" (at 59.69 182.88 0)
      (effects (font (size 1.27 1.27) (thickness 0.15)) (justify left bottom) hide)
    )
    (property "License" "Apache-2.0" (at 59.69 185.42 0)
      (effects (font (size 1.27 1.27) (thickness 0.15)) (justify left bottom) hide)
    )
    (pin "1")
    (instances
      (project "data-center-rdimm-ddr4-tester"
        (path ""
          (reference "#PWR0362") (unit 1)
        )
      )
    )
  )

  (symbol (lib_id "antmicropower:GND") (at 341.63 116.205 0) (unit 1)
    (in_bom yes) (on_board yes) (dnp no) (fields_autoplaced)
    (property "Reference" "#PWR0224" (at 341.63 122.555 0)
      (effects (font (size 1.27 1.27)) hide)
    )
    (property "Value" "GND" (at 341.63 120.65 0)
      (effects (font (size 1.27 1.27)))
    )
    (property "Footprint" "" (at 341.63 116.205 0)
      (effects (font (size 1.27 1.27)) hide)
    )
    (property "Datasheet" "" (at 341.63 116.205 0)
      (effects (font (size 1.27 1.27)) hide)
    )
    (property "Author" "Antmicro" (at 350.52 123.825 0)
      (effects (font (size 1.27 1.27) (thickness 0.15)) (justify left bottom) hide)
    )
    (property "License" "Apache-2.0" (at 350.52 126.365 0)
      (effects (font (size 1.27 1.27) (thickness 0.15)) (justify left bottom) hide)
    )
    (pin "1")
    (instances
      (project "data-center-rdimm-ddr4-tester"
        (path ""
          (reference "#PWR0224") (unit 1)
        )
      )
    )
  )

  (symbol (lib_id "antmicroCapacitorsmisc:C_100n_0201") (at 29.845 170.18 270) (unit 1)
    (in_bom yes) (on_board yes) (dnp no)
    (property "Reference" "C231" (at 29.845 170.815 90)
      (effects (font (size 1.524 1.524)) (justify left))
    )
    (property "Value" "C_100n_0201" (at 19.685 190.5 0)
      (effects (font (size 1.27 1.27) (thickness 0.15)) (justify left bottom) hide)
    )
    (property "Footprint" "antmicro-footprints:C_0201" (at 17.145 190.5 0)
      (effects (font (size 1.27 1.27) (thickness 0.15)) (justify left bottom) hide)
    )
    (property "Datasheet" " " (at 14.605 190.5 0)
      (effects (font (size 1.27 1.27) (thickness 0.15)) (justify left bottom) hide)
    )
    (property "Manufacturer" "Yaego" (at 9.525 190.5 0)
      (effects (font (size 1.27 1.27) (thickness 0.15)) (justify left bottom) hide)
    )
    (property "MPN" "CC0201KRX6S5BB104" (at 12.065 190.5 0)
      (effects (font (size 1.27 1.27) (thickness 0.15)) (justify left bottom) hide)
    )
    (property "Val" "100n" (at 29.845 174.625 90)
      (effects (font (size 1.27 1.27) (thickness 0.15)) (justify left))
    )
    (property "License" "Apache-2.0" (at 6.985 190.5 0)
      (effects (font (size 1.27 1.27) (thickness 0.15)) (justify left bottom) hide)
    )
    (property "Author" "Antmicro" (at 4.445 190.5 0)
      (effects (font (size 1.27 1.27) (thickness 0.15)) (justify left bottom) hide)
    )
    (property "Voltage" "" (at 1.905 190.5 0)
      (effects (font (size 1.27 1.27)) (justify left bottom) hide)
    )
    (property "Dielectric" "" (at -0.635 190.5 0)
      (effects (font (size 1.27 1.27)) (justify left bottom) hide)
    )
    (pin "1")
    (pin "2")
    (instances
      (project "data-center-rdimm-ddr4-tester"
        (path ""
          (reference "C231") (unit 1)
        )
      )
    )
  )

  (symbol (lib_id "antmicropower:GND") (at 285.115 116.205 0) (unit 1)
    (in_bom yes) (on_board yes) (dnp no) (fields_autoplaced)
    (property "Reference" "#PWR0327" (at 285.115 122.555 0)
      (effects (font (size 1.27 1.27)) hide)
    )
    (property "Value" "GND" (at 285.115 120.65 0)
      (effects (font (size 1.27 1.27)))
    )
    (property "Footprint" "" (at 285.115 116.205 0)
      (effects (font (size 1.27 1.27)) hide)
    )
    (property "Datasheet" "" (at 285.115 116.205 0)
      (effects (font (size 1.27 1.27)) hide)
    )
    (property "Author" "Antmicro" (at 294.005 123.825 0)
      (effects (font (size 1.27 1.27) (thickness 0.15)) (justify left bottom) hide)
    )
    (property "License" "Apache-2.0" (at 294.005 126.365 0)
      (effects (font (size 1.27 1.27) (thickness 0.15)) (justify left bottom) hide)
    )
    (pin "1")
    (instances
      (project "data-center-rdimm-ddr4-tester"
        (path ""
          (reference "#PWR0327") (unit 1)
        )
      )
    )
  )

  (symbol (lib_id "antmicroCapacitorsmisc:C_100n_0201") (at 255.27 111.125 270) (unit 1)
    (in_bom yes) (on_board yes) (dnp no)
    (property "Reference" "C240" (at 255.905 111.76 90)
      (effects (font (size 1.524 1.524)) (justify left))
    )
    (property "Value" "C_100n_0201" (at 245.11 131.445 0)
      (effects (font (size 1.27 1.27) (thickness 0.15)) (justify left bottom) hide)
    )
    (property "Footprint" "antmicro-footprints:C_0201" (at 242.57 131.445 0)
      (effects (font (size 1.27 1.27) (thickness 0.15)) (justify left bottom) hide)
    )
    (property "Datasheet" " " (at 240.03 131.445 0)
      (effects (font (size 1.27 1.27) (thickness 0.15)) (justify left bottom) hide)
    )
    (property "Manufacturer" "Yaego" (at 234.95 131.445 0)
      (effects (font (size 1.27 1.27) (thickness 0.15)) (justify left bottom) hide)
    )
    (property "MPN" "CC0201KRX6S5BB104" (at 237.49 131.445 0)
      (effects (font (size 1.27 1.27) (thickness 0.15)) (justify left bottom) hide)
    )
    (property "Val" "100n" (at 255.905 115.57 90)
      (effects (font (size 1.27 1.27) (thickness 0.15)) (justify left))
    )
    (property "License" "Apache-2.0" (at 232.41 131.445 0)
      (effects (font (size 1.27 1.27) (thickness 0.15)) (justify left bottom) hide)
    )
    (property "Author" "Antmicro" (at 229.87 131.445 0)
      (effects (font (size 1.27 1.27) (thickness 0.15)) (justify left bottom) hide)
    )
    (property "Voltage" "" (at 227.33 131.445 0)
      (effects (font (size 1.27 1.27)) (justify left bottom) hide)
    )
    (property "Dielectric" "" (at 224.79 131.445 0)
      (effects (font (size 1.27 1.27)) (justify left bottom) hide)
    )
    (pin "1")
    (pin "2")
    (instances
      (project "data-center-rdimm-ddr4-tester"
        (path ""
          (reference "C240") (unit 1)
        )
      )
    )
  )

  (symbol (lib_id "antmicroCapacitorsmisc:C_100n_0201") (at 99.695 170.18 270) (unit 1)
    (in_bom yes) (on_board yes) (dnp no)
    (property "Reference" "C79" (at 99.695 170.815 90)
      (effects (font (size 1.524 1.524)) (justify left))
    )
    (property "Value" "C_100n_0201" (at 89.535 190.5 0)
      (effects (font (size 1.27 1.27) (thickness 0.15)) (justify left bottom) hide)
    )
    (property "Footprint" "antmicro-footprints:C_0201" (at 86.995 190.5 0)
      (effects (font (size 1.27 1.27) (thickness 0.15)) (justify left bottom) hide)
    )
    (property "Datasheet" " " (at 84.455 190.5 0)
      (effects (font (size 1.27 1.27) (thickness 0.15)) (justify left bottom) hide)
    )
    (property "Manufacturer" "Yaego" (at 79.375 190.5 0)
      (effects (font (size 1.27 1.27) (thickness 0.15)) (justify left bottom) hide)
    )
    (property "MPN" "CC0201KRX6S5BB104" (at 81.915 190.5 0)
      (effects (font (size 1.27 1.27) (thickness 0.15)) (justify left bottom) hide)
    )
    (property "Val" "100n" (at 99.695 174.625 90)
      (effects (font (size 1.27 1.27) (thickness 0.15)) (justify left))
    )
    (property "License" "Apache-2.0" (at 76.835 190.5 0)
      (effects (font (size 1.27 1.27) (thickness 0.15)) (justify left bottom) hide)
    )
    (property "Author" "Antmicro" (at 74.295 190.5 0)
      (effects (font (size 1.27 1.27) (thickness 0.15)) (justify left bottom) hide)
    )
    (property "Voltage" "" (at 71.755 190.5 0)
      (effects (font (size 1.27 1.27)) (justify left bottom) hide)
    )
    (property "Dielectric" "" (at 69.215 190.5 0)
      (effects (font (size 1.27 1.27)) (justify left bottom) hide)
    )
    (pin "1")
    (pin "2")
    (instances
      (project "data-center-rdimm-ddr4-tester"
        (path ""
          (reference "C79") (unit 1)
        )
      )
    )
  )

  (symbol (lib_id "antmicroCapacitorsmisc:C_100n_0201") (at 35.56 232.41 270) (unit 1)
    (in_bom yes) (on_board yes) (dnp no)
    (property "Reference" "C83" (at 35.56 233.045 90)
      (effects (font (size 1.524 1.524)) (justify left))
    )
    (property "Value" "C_100n_0201" (at 25.4 252.73 0)
      (effects (font (size 1.27 1.27) (thickness 0.15)) (justify left bottom) hide)
    )
    (property "Footprint" "antmicro-footprints:C_0201" (at 22.86 252.73 0)
      (effects (font (size 1.27 1.27) (thickness 0.15)) (justify left bottom) hide)
    )
    (property "Datasheet" " " (at 20.32 252.73 0)
      (effects (font (size 1.27 1.27) (thickness 0.15)) (justify left bottom) hide)
    )
    (property "Manufacturer" "Yaego" (at 15.24 252.73 0)
      (effects (font (size 1.27 1.27) (thickness 0.15)) (justify left bottom) hide)
    )
    (property "MPN" "CC0201KRX6S5BB104" (at 17.78 252.73 0)
      (effects (font (size 1.27 1.27) (thickness 0.15)) (justify left bottom) hide)
    )
    (property "Val" "100n" (at 35.56 236.855 90)
      (effects (font (size 1.27 1.27) (thickness 0.15)) (justify left))
    )
    (property "License" "Apache-2.0" (at 12.7 252.73 0)
      (effects (font (size 1.27 1.27) (thickness 0.15)) (justify left bottom) hide)
    )
    (property "Author" "Antmicro" (at 10.16 252.73 0)
      (effects (font (size 1.27 1.27) (thickness 0.15)) (justify left bottom) hide)
    )
    (property "Voltage" "" (at 7.62 252.73 0)
      (effects (font (size 1.27 1.27)) (justify left bottom) hide)
    )
    (property "Dielectric" "" (at 5.08 252.73 0)
      (effects (font (size 1.27 1.27)) (justify left bottom) hide)
    )
    (pin "1")
    (pin "2")
    (instances
      (project "data-center-rdimm-ddr4-tester"
        (path ""
          (reference "C83") (unit 1)
        )
      )
    )
  )

  (symbol (lib_id "antmicropower:GND") (at 55.245 237.49 0) (unit 1)
    (in_bom yes) (on_board yes) (dnp no) (fields_autoplaced)
    (property "Reference" "#PWR0379" (at 55.245 243.84 0)
      (effects (font (size 1.27 1.27)) hide)
    )
    (property "Value" "GND" (at 55.245 241.935 0)
      (effects (font (size 1.27 1.27)))
    )
    (property "Footprint" "" (at 55.245 237.49 0)
      (effects (font (size 1.27 1.27)) hide)
    )
    (property "Datasheet" "" (at 55.245 237.49 0)
      (effects (font (size 1.27 1.27)) hide)
    )
    (property "Author" "Antmicro" (at 64.135 245.11 0)
      (effects (font (size 1.27 1.27) (thickness 0.15)) (justify left bottom) hide)
    )
    (property "License" "Apache-2.0" (at 64.135 247.65 0)
      (effects (font (size 1.27 1.27) (thickness 0.15)) (justify left bottom) hide)
    )
    (pin "1")
    (instances
      (project "data-center-rdimm-ddr4-tester"
        (path ""
          (reference "#PWR0379") (unit 1)
        )
      )
    )
  )

  (symbol (lib_id "antmicropower:GND") (at 30.48 140.335 0) (unit 1)
    (in_bom yes) (on_board yes) (dnp no) (fields_autoplaced)
    (property "Reference" "#PWR0245" (at 30.48 146.685 0)
      (effects (font (size 1.27 1.27)) hide)
    )
    (property "Value" "GND" (at 30.48 144.78 0)
      (effects (font (size 1.27 1.27)))
    )
    (property "Footprint" "" (at 30.48 140.335 0)
      (effects (font (size 1.27 1.27)) hide)
    )
    (property "Datasheet" "" (at 30.48 140.335 0)
      (effects (font (size 1.27 1.27)) hide)
    )
    (property "Author" "Antmicro" (at 39.37 147.955 0)
      (effects (font (size 1.27 1.27) (thickness 0.15)) (justify left bottom) hide)
    )
    (property "License" "Apache-2.0" (at 39.37 150.495 0)
      (effects (font (size 1.27 1.27) (thickness 0.15)) (justify left bottom) hide)
    )
    (pin "1")
    (instances
      (project "data-center-rdimm-ddr4-tester"
        (path ""
          (reference "#PWR0245") (unit 1)
        )
      )
    )
  )

  (symbol (lib_id "antmicroCapacitorsmisc:C_100n_0201") (at 69.215 201.295 270) (unit 1)
    (in_bom yes) (on_board yes) (dnp no)
    (property "Reference" "C88" (at 69.215 201.93 90)
      (effects (font (size 1.524 1.524)) (justify left))
    )
    (property "Value" "C_100n_0201" (at 59.055 221.615 0)
      (effects (font (size 1.27 1.27) (thickness 0.15)) (justify left bottom) hide)
    )
    (property "Footprint" "antmicro-footprints:C_0201" (at 56.515 221.615 0)
      (effects (font (size 1.27 1.27) (thickness 0.15)) (justify left bottom) hide)
    )
    (property "Datasheet" " " (at 53.975 221.615 0)
      (effects (font (size 1.27 1.27) (thickness 0.15)) (justify left bottom) hide)
    )
    (property "Manufacturer" "Yaego" (at 48.895 221.615 0)
      (effects (font (size 1.27 1.27) (thickness 0.15)) (justify left bottom) hide)
    )
    (property "MPN" "CC0201KRX6S5BB104" (at 51.435 221.615 0)
      (effects (font (size 1.27 1.27) (thickness 0.15)) (justify left bottom) hide)
    )
    (property "Val" "100n" (at 69.215 205.74 90)
      (effects (font (size 1.27 1.27) (thickness 0.15)) (justify left))
    )
    (property "License" "Apache-2.0" (at 46.355 221.615 0)
      (effects (font (size 1.27 1.27) (thickness 0.15)) (justify left bottom) hide)
    )
    (property "Author" "Antmicro" (at 43.815 221.615 0)
      (effects (font (size 1.27 1.27) (thickness 0.15)) (justify left bottom) hide)
    )
    (property "Voltage" "" (at 41.275 221.615 0)
      (effects (font (size 1.27 1.27)) (justify left bottom) hide)
    )
    (property "Dielectric" "" (at 38.735 221.615 0)
      (effects (font (size 1.27 1.27)) (justify left bottom) hide)
    )
    (pin "1")
    (pin "2")
    (instances
      (project "data-center-rdimm-ddr4-tester"
        (path ""
          (reference "C88") (unit 1)
        )
      )
    )
  )

  (symbol (lib_id "antmicropower:GND") (at 95.25 237.49 0) (unit 1)
    (in_bom yes) (on_board yes) (dnp no) (fields_autoplaced)
    (property "Reference" "#PWR0388" (at 95.25 243.84 0)
      (effects (font (size 1.27 1.27)) hide)
    )
    (property "Value" "GND" (at 95.25 241.935 0)
      (effects (font (size 1.27 1.27)))
    )
    (property "Footprint" "" (at 95.25 237.49 0)
      (effects (font (size 1.27 1.27)) hide)
    )
    (property "Datasheet" "" (at 95.25 237.49 0)
      (effects (font (size 1.27 1.27)) hide)
    )
    (property "Author" "Antmicro" (at 104.14 245.11 0)
      (effects (font (size 1.27 1.27) (thickness 0.15)) (justify left bottom) hide)
    )
    (property "License" "Apache-2.0" (at 104.14 247.65 0)
      (effects (font (size 1.27 1.27) (thickness 0.15)) (justify left bottom) hide)
    )
    (pin "1")
    (instances
      (project "data-center-rdimm-ddr4-tester"
        (path ""
          (reference "#PWR0388") (unit 1)
        )
      )
    )
  )

  (symbol (lib_id "antmicroCapacitorsmisc:C_100n_0201") (at 285.115 111.125 270) (unit 1)
    (in_bom yes) (on_board yes) (dnp no)
    (property "Reference" "C244" (at 285.75 111.76 90)
      (effects (font (size 1.524 1.524)) (justify left))
    )
    (property "Value" "C_100n_0201" (at 274.955 131.445 0)
      (effects (font (size 1.27 1.27) (thickness 0.15)) (justify left bottom) hide)
    )
    (property "Footprint" "antmicro-footprints:C_0201" (at 272.415 131.445 0)
      (effects (font (size 1.27 1.27) (thickness 0.15)) (justify left bottom) hide)
    )
    (property "Datasheet" " " (at 269.875 131.445 0)
      (effects (font (size 1.27 1.27) (thickness 0.15)) (justify left bottom) hide)
    )
    (property "Manufacturer" "Yaego" (at 264.795 131.445 0)
      (effects (font (size 1.27 1.27) (thickness 0.15)) (justify left bottom) hide)
    )
    (property "MPN" "CC0201KRX6S5BB104" (at 267.335 131.445 0)
      (effects (font (size 1.27 1.27) (thickness 0.15)) (justify left bottom) hide)
    )
    (property "Val" "100n" (at 286.385 115.57 90)
      (effects (font (size 1.27 1.27) (thickness 0.15)) (justify left))
    )
    (property "License" "Apache-2.0" (at 262.255 131.445 0)
      (effects (font (size 1.27 1.27) (thickness 0.15)) (justify left bottom) hide)
    )
    (property "Author" "Antmicro" (at 259.715 131.445 0)
      (effects (font (size 1.27 1.27) (thickness 0.15)) (justify left bottom) hide)
    )
    (property "Voltage" "" (at 257.175 131.445 0)
      (effects (font (size 1.27 1.27)) (justify left bottom) hide)
    )
    (property "Dielectric" "" (at 254.635 131.445 0)
      (effects (font (size 1.27 1.27)) (justify left bottom) hide)
    )
    (pin "1")
    (pin "2")
    (instances
      (project "data-center-rdimm-ddr4-tester"
        (path ""
          (reference "C244") (unit 1)
        )
      )
    )
  )

  (symbol (lib_id "antmicroCapacitorsmisc:C_100n_0201") (at 75.565 232.41 270) (unit 1)
    (in_bom yes) (on_board yes) (dnp no)
    (property "Reference" "C305" (at 75.565 233.045 90)
      (effects (font (size 1.524 1.524)) (justify left))
    )
    (property "Value" "C_100n_0201" (at 65.405 252.73 0)
      (effects (font (size 1.27 1.27) (thickness 0.15)) (justify left bottom) hide)
    )
    (property "Footprint" "antmicro-footprints:C_0201" (at 62.865 252.73 0)
      (effects (font (size 1.27 1.27) (thickness 0.15)) (justify left bottom) hide)
    )
    (property "Datasheet" " " (at 60.325 252.73 0)
      (effects (font (size 1.27 1.27) (thickness 0.15)) (justify left bottom) hide)
    )
    (property "Manufacturer" "Yaego" (at 55.245 252.73 0)
      (effects (font (size 1.27 1.27) (thickness 0.15)) (justify left bottom) hide)
    )
    (property "MPN" "CC0201KRX6S5BB104" (at 57.785 252.73 0)
      (effects (font (size 1.27 1.27) (thickness 0.15)) (justify left bottom) hide)
    )
    (property "Val" "100n" (at 75.565 236.855 90)
      (effects (font (size 1.27 1.27) (thickness 0.15)) (justify left))
    )
    (property "License" "Apache-2.0" (at 52.705 252.73 0)
      (effects (font (size 1.27 1.27) (thickness 0.15)) (justify left bottom) hide)
    )
    (property "Author" "Antmicro" (at 50.165 252.73 0)
      (effects (font (size 1.27 1.27) (thickness 0.15)) (justify left bottom) hide)
    )
    (property "Voltage" "" (at 47.625 252.73 0)
      (effects (font (size 1.27 1.27)) (justify left bottom) hide)
    )
    (property "Dielectric" "" (at 45.085 252.73 0)
      (effects (font (size 1.27 1.27)) (justify left bottom) hide)
    )
    (pin "1")
    (pin "2")
    (instances
      (project "data-center-rdimm-ddr4-tester"
        (path ""
          (reference "C305") (unit 1)
        )
      )
    )
  )

  (symbol (lib_id "antmicropower:GND") (at 81.915 237.49 0) (unit 1)
    (in_bom yes) (on_board yes) (dnp no) (fields_autoplaced)
    (property "Reference" "#PWR0390" (at 81.915 243.84 0)
      (effects (font (size 1.27 1.27)) hide)
    )
    (property "Value" "GND" (at 81.915 241.935 0)
      (effects (font (size 1.27 1.27)))
    )
    (property "Footprint" "" (at 81.915 237.49 0)
      (effects (font (size 1.27 1.27)) hide)
    )
    (property "Datasheet" "" (at 81.915 237.49 0)
      (effects (font (size 1.27 1.27)) hide)
    )
    (property "Author" "Antmicro" (at 90.805 245.11 0)
      (effects (font (size 1.27 1.27) (thickness 0.15)) (justify left bottom) hide)
    )
    (property "License" "Apache-2.0" (at 90.805 247.65 0)
      (effects (font (size 1.27 1.27) (thickness 0.15)) (justify left bottom) hide)
    )
    (pin "1")
    (instances
      (project "data-center-rdimm-ddr4-tester"
        (path ""
          (reference "#PWR0390") (unit 1)
        )
      )
    )
  )

  (symbol (lib_id "antmicropower:GND") (at 48.895 237.49 0) (unit 1)
    (in_bom yes) (on_board yes) (dnp no) (fields_autoplaced)
    (property "Reference" "#PWR0378" (at 48.895 243.84 0)
      (effects (font (size 1.27 1.27)) hide)
    )
    (property "Value" "GND" (at 48.895 241.935 0)
      (effects (font (size 1.27 1.27)))
    )
    (property "Footprint" "" (at 48.895 237.49 0)
      (effects (font (size 1.27 1.27)) hide)
    )
    (property "Datasheet" "" (at 48.895 237.49 0)
      (effects (font (size 1.27 1.27)) hide)
    )
    (property "Author" "Antmicro" (at 57.785 245.11 0)
      (effects (font (size 1.27 1.27) (thickness 0.15)) (justify left bottom) hide)
    )
    (property "License" "Apache-2.0" (at 57.785 247.65 0)
      (effects (font (size 1.27 1.27) (thickness 0.15)) (justify left bottom) hide)
    )
    (pin "1")
    (instances
      (project "data-center-rdimm-ddr4-tester"
        (path ""
          (reference "#PWR0378") (unit 1)
        )
      )
    )
  )

  (symbol (lib_id "antmicropower:GND") (at 29.845 175.26 0) (unit 1)
    (in_bom yes) (on_board yes) (dnp no) (fields_autoplaced)
    (property "Reference" "#PWR0367" (at 29.845 181.61 0)
      (effects (font (size 1.27 1.27)) hide)
    )
    (property "Value" "GND" (at 29.845 179.705 0)
      (effects (font (size 1.27 1.27)))
    )
    (property "Footprint" "" (at 29.845 175.26 0)
      (effects (font (size 1.27 1.27)) hide)
    )
    (property "Datasheet" "" (at 29.845 175.26 0)
      (effects (font (size 1.27 1.27)) hide)
    )
    (property "Author" "Antmicro" (at 38.735 182.88 0)
      (effects (font (size 1.27 1.27) (thickness 0.15)) (justify left bottom) hide)
    )
    (property "License" "Apache-2.0" (at 38.735 185.42 0)
      (effects (font (size 1.27 1.27) (thickness 0.15)) (justify left bottom) hide)
    )
    (pin "1")
    (instances
      (project "data-center-rdimm-ddr4-tester"
        (path ""
          (reference "#PWR0367") (unit 1)
        )
      )
    )
  )

  (symbol (lib_id "antmicroCapacitorsmisc:C_100n_0201") (at 89.535 201.295 270) (unit 1)
    (in_bom yes) (on_board yes) (dnp no)
    (property "Reference" "C91" (at 89.535 201.93 90)
      (effects (font (size 1.524 1.524)) (justify left))
    )
    (property "Value" "C_100n_0201" (at 79.375 221.615 0)
      (effects (font (size 1.27 1.27) (thickness 0.15)) (justify left bottom) hide)
    )
    (property "Footprint" "antmicro-footprints:C_0201" (at 76.835 221.615 0)
      (effects (font (size 1.27 1.27) (thickness 0.15)) (justify left bottom) hide)
    )
    (property "Datasheet" " " (at 74.295 221.615 0)
      (effects (font (size 1.27 1.27) (thickness 0.15)) (justify left bottom) hide)
    )
    (property "Manufacturer" "Yaego" (at 69.215 221.615 0)
      (effects (font (size 1.27 1.27) (thickness 0.15)) (justify left bottom) hide)
    )
    (property "MPN" "CC0201KRX6S5BB104" (at 71.755 221.615 0)
      (effects (font (size 1.27 1.27) (thickness 0.15)) (justify left bottom) hide)
    )
    (property "Val" "100n" (at 89.535 205.74 90)
      (effects (font (size 1.27 1.27) (thickness 0.15)) (justify left))
    )
    (property "License" "Apache-2.0" (at 66.675 221.615 0)
      (effects (font (size 1.27 1.27) (thickness 0.15)) (justify left bottom) hide)
    )
    (property "Author" "Antmicro" (at 64.135 221.615 0)
      (effects (font (size 1.27 1.27) (thickness 0.15)) (justify left bottom) hide)
    )
    (property "Voltage" "" (at 61.595 221.615 0)
      (effects (font (size 1.27 1.27)) (justify left bottom) hide)
    )
    (property "Dielectric" "" (at 59.055 221.615 0)
      (effects (font (size 1.27 1.27)) (justify left bottom) hide)
    )
    (pin "1")
    (pin "2")
    (instances
      (project "data-center-rdimm-ddr4-tester"
        (path ""
          (reference "C91") (unit 1)
        )
      )
    )
  )

  (symbol (lib_id "antmicroCapacitorsmisc:C_100n_0201") (at 219.71 111.125 270) (unit 1)
    (in_bom yes) (on_board yes) (dnp no) (fields_autoplaced)
    (property "Reference" "C238" (at 222.25 112.4013 90)
      (effects (font (size 1.524 1.524)) (justify left))
    )
    (property "Value" "C_100n_0201" (at 209.55 131.445 0)
      (effects (font (size 1.27 1.27) (thickness 0.15)) (justify left bottom) hide)
    )
    (property "Footprint" "antmicro-footprints:C_0201" (at 207.01 131.445 0)
      (effects (font (size 1.27 1.27) (thickness 0.15)) (justify left bottom) hide)
    )
    (property "Datasheet" " " (at 204.47 131.445 0)
      (effects (font (size 1.27 1.27) (thickness 0.15)) (justify left bottom) hide)
    )
    (property "Manufacturer" "Yaego" (at 199.39 131.445 0)
      (effects (font (size 1.27 1.27) (thickness 0.15)) (justify left bottom) hide)
    )
    (property "MPN" "CC0201KRX6S5BB104" (at 201.93 131.445 0)
      (effects (font (size 1.27 1.27) (thickness 0.15)) (justify left bottom) hide)
    )
    (property "Val" "100n" (at 222.25 115.5762 90)
      (effects (font (size 1.27 1.27) (thickness 0.15)) (justify left))
    )
    (property "License" "Apache-2.0" (at 196.85 131.445 0)
      (effects (font (size 1.27 1.27) (thickness 0.15)) (justify left bottom) hide)
    )
    (property "Author" "Antmicro" (at 194.31 131.445 0)
      (effects (font (size 1.27 1.27) (thickness 0.15)) (justify left bottom) hide)
    )
    (property "Voltage" "" (at 191.77 131.445 0)
      (effects (font (size 1.27 1.27)) (justify left bottom) hide)
    )
    (property "Dielectric" "" (at 189.23 131.445 0)
      (effects (font (size 1.27 1.27)) (justify left bottom) hide)
    )
    (pin "1")
    (pin "2")
    (instances
      (project "data-center-rdimm-ddr4-tester"
        (path ""
          (reference "C238") (unit 1)
        )
      )
    )
  )

  (symbol (lib_id "antmicropower:GND") (at 356.235 116.205 0) (unit 1)
    (in_bom yes) (on_board yes) (dnp no) (fields_autoplaced)
    (property "Reference" "#PWR0140" (at 356.235 122.555 0)
      (effects (font (size 1.27 1.27)) hide)
    )
    (property "Value" "GND" (at 356.235 120.65 0)
      (effects (font (size 1.27 1.27)))
    )
    (property "Footprint" "" (at 356.235 116.205 0)
      (effects (font (size 1.27 1.27)) hide)
    )
    (property "Datasheet" "" (at 356.235 116.205 0)
      (effects (font (size 1.27 1.27)) hide)
    )
    (property "Author" "Antmicro" (at 365.125 123.825 0)
      (effects (font (size 1.27 1.27) (thickness 0.15)) (justify left bottom) hide)
    )
    (property "License" "Apache-2.0" (at 365.125 126.365 0)
      (effects (font (size 1.27 1.27) (thickness 0.15)) (justify left bottom) hide)
    )
    (pin "1")
    (instances
      (project "data-center-rdimm-ddr4-tester"
        (path ""
          (reference "#PWR0140") (unit 1)
        )
      )
    )
  )

  (symbol (lib_id "antmicroCapacitorsmisc:C_100n_0201") (at 62.23 232.41 270) (unit 1)
    (in_bom yes) (on_board yes) (dnp no)
    (property "Reference" "C303" (at 62.23 233.045 90)
      (effects (font (size 1.524 1.524)) (justify left))
    )
    (property "Value" "C_100n_0201" (at 52.07 252.73 0)
      (effects (font (size 1.27 1.27) (thickness 0.15)) (justify left bottom) hide)
    )
    (property "Footprint" "antmicro-footprints:C_0201" (at 49.53 252.73 0)
      (effects (font (size 1.27 1.27) (thickness 0.15)) (justify left bottom) hide)
    )
    (property "Datasheet" " " (at 46.99 252.73 0)
      (effects (font (size 1.27 1.27) (thickness 0.15)) (justify left bottom) hide)
    )
    (property "Manufacturer" "Yaego" (at 41.91 252.73 0)
      (effects (font (size 1.27 1.27) (thickness 0.15)) (justify left bottom) hide)
    )
    (property "MPN" "CC0201KRX6S5BB104" (at 44.45 252.73 0)
      (effects (font (size 1.27 1.27) (thickness 0.15)) (justify left bottom) hide)
    )
    (property "Val" "100n" (at 62.23 236.855 90)
      (effects (font (size 1.27 1.27) (thickness 0.15)) (justify left))
    )
    (property "License" "Apache-2.0" (at 39.37 252.73 0)
      (effects (font (size 1.27 1.27) (thickness 0.15)) (justify left bottom) hide)
    )
    (property "Author" "Antmicro" (at 36.83 252.73 0)
      (effects (font (size 1.27 1.27) (thickness 0.15)) (justify left bottom) hide)
    )
    (property "Voltage" "" (at 34.29 252.73 0)
      (effects (font (size 1.27 1.27)) (justify left bottom) hide)
    )
    (property "Dielectric" "" (at 31.75 252.73 0)
      (effects (font (size 1.27 1.27)) (justify left bottom) hide)
    )
    (pin "1")
    (pin "2")
    (instances
      (project "data-center-rdimm-ddr4-tester"
        (path ""
          (reference "C303") (unit 1)
        )
      )
    )
  )

  (symbol (lib_id "antmicroCapacitorsmisc:C_100n_0201") (at 48.895 232.41 270) (unit 1)
    (in_bom yes) (on_board yes) (dnp no)
    (property "Reference" "C85" (at 48.895 233.045 90)
      (effects (font (size 1.524 1.524)) (justify left))
    )
    (property "Value" "C_100n_0201" (at 38.735 252.73 0)
      (effects (font (size 1.27 1.27) (thickness 0.15)) (justify left bottom) hide)
    )
    (property "Footprint" "antmicro-footprints:C_0201" (at 36.195 252.73 0)
      (effects (font (size 1.27 1.27) (thickness 0.15)) (justify left bottom) hide)
    )
    (property "Datasheet" " " (at 33.655 252.73 0)
      (effects (font (size 1.27 1.27) (thickness 0.15)) (justify left bottom) hide)
    )
    (property "Manufacturer" "Yaego" (at 28.575 252.73 0)
      (effects (font (size 1.27 1.27) (thickness 0.15)) (justify left bottom) hide)
    )
    (property "MPN" "CC0201KRX6S5BB104" (at 31.115 252.73 0)
      (effects (font (size 1.27 1.27) (thickness 0.15)) (justify left bottom) hide)
    )
    (property "Val" "100n" (at 48.895 236.855 90)
      (effects (font (size 1.27 1.27) (thickness 0.15)) (justify left))
    )
    (property "License" "Apache-2.0" (at 26.035 252.73 0)
      (effects (font (size 1.27 1.27) (thickness 0.15)) (justify left bottom) hide)
    )
    (property "Author" "Antmicro" (at 23.495 252.73 0)
      (effects (font (size 1.27 1.27) (thickness 0.15)) (justify left bottom) hide)
    )
    (property "Voltage" "" (at 20.955 252.73 0)
      (effects (font (size 1.27 1.27)) (justify left bottom) hide)
    )
    (property "Dielectric" "" (at 18.415 252.73 0)
      (effects (font (size 1.27 1.27)) (justify left bottom) hide)
    )
    (pin "1")
    (pin "2")
    (instances
      (project "data-center-rdimm-ddr4-tester"
        (path ""
          (reference "C85") (unit 1)
        )
      )
    )
  )

  (symbol (lib_id "antmicropower:GND") (at 379.095 116.205 0) (unit 1)
    (in_bom yes) (on_board yes) (dnp no) (fields_autoplaced)
    (property "Reference" "#PWR0221" (at 379.095 122.555 0)
      (effects (font (size 1.27 1.27)) hide)
    )
    (property "Value" "GND" (at 379.095 120.65 0)
      (effects (font (size 1.27 1.27)))
    )
    (property "Footprint" "" (at 379.095 116.205 0)
      (effects (font (size 1.27 1.27)) hide)
    )
    (property "Datasheet" "" (at 379.095 116.205 0)
      (effects (font (size 1.27 1.27)) hide)
    )
    (property "Author" "Antmicro" (at 387.985 123.825 0)
      (effects (font (size 1.27 1.27) (thickness 0.15)) (justify left bottom) hide)
    )
    (property "License" "Apache-2.0" (at 387.985 126.365 0)
      (effects (font (size 1.27 1.27) (thickness 0.15)) (justify left bottom) hide)
    )
    (pin "1")
    (instances
      (project "data-center-rdimm-ddr4-tester"
        (path ""
          (reference "#PWR0221") (unit 1)
        )
      )
    )
  )

  (symbol (lib_id "antmicroCapacitorsmisc:C_100n_0201") (at 95.25 232.41 270) (unit 1)
    (in_bom yes) (on_board yes) (dnp no)
    (property "Reference" "C308" (at 95.25 233.045 90)
      (effects (font (size 1.524 1.524)) (justify left))
    )
    (property "Value" "C_100n_0201" (at 85.09 252.73 0)
      (effects (font (size 1.27 1.27) (thickness 0.15)) (justify left bottom) hide)
    )
    (property "Footprint" "antmicro-footprints:C_0201" (at 82.55 252.73 0)
      (effects (font (size 1.27 1.27) (thickness 0.15)) (justify left bottom) hide)
    )
    (property "Datasheet" " " (at 80.01 252.73 0)
      (effects (font (size 1.27 1.27) (thickness 0.15)) (justify left bottom) hide)
    )
    (property "Manufacturer" "Yaego" (at 74.93 252.73 0)
      (effects (font (size 1.27 1.27) (thickness 0.15)) (justify left bottom) hide)
    )
    (property "MPN" "CC0201KRX6S5BB104" (at 77.47 252.73 0)
      (effects (font (size 1.27 1.27) (thickness 0.15)) (justify left bottom) hide)
    )
    (property "Val" "100n" (at 95.25 236.855 90)
      (effects (font (size 1.27 1.27) (thickness 0.15)) (justify left))
    )
    (property "License" "Apache-2.0" (at 72.39 252.73 0)
      (effects (font (size 1.27 1.27) (thickness 0.15)) (justify left bottom) hide)
    )
    (property "Author" "Antmicro" (at 69.85 252.73 0)
      (effects (font (size 1.27 1.27) (thickness 0.15)) (justify left bottom) hide)
    )
    (property "Voltage" "" (at 67.31 252.73 0)
      (effects (font (size 1.27 1.27)) (justify left bottom) hide)
    )
    (property "Dielectric" "" (at 64.77 252.73 0)
      (effects (font (size 1.27 1.27)) (justify left bottom) hide)
    )
    (pin "1")
    (pin "2")
    (instances
      (project "data-center-rdimm-ddr4-tester"
        (path ""
          (reference "C308") (unit 1)
        )
      )
    )
  )

  (symbol (lib_id "antmicroCapacitorsmisc:C_100n_0201") (at 341.63 111.125 270) (unit 1)
    (in_bom yes) (on_board yes) (dnp no)
    (property "Reference" "C250" (at 342.265 111.76 90)
      (effects (font (size 1.524 1.524)) (justify left))
    )
    (property "Value" "C_100n_0201" (at 331.47 131.445 0)
      (effects (font (size 1.27 1.27) (thickness 0.15)) (justify left bottom) hide)
    )
    (property "Footprint" "antmicro-footprints:C_0201" (at 328.93 131.445 0)
      (effects (font (size 1.27 1.27) (thickness 0.15)) (justify left bottom) hide)
    )
    (property "Datasheet" " " (at 326.39 131.445 0)
      (effects (font (size 1.27 1.27) (thickness 0.15)) (justify left bottom) hide)
    )
    (property "Manufacturer" "Yaego" (at 321.31 131.445 0)
      (effects (font (size 1.27 1.27) (thickness 0.15)) (justify left bottom) hide)
    )
    (property "MPN" "CC0201KRX6S5BB104" (at 323.85 131.445 0)
      (effects (font (size 1.27 1.27) (thickness 0.15)) (justify left bottom) hide)
    )
    (property "Val" "100n" (at 342.265 115.57 90)
      (effects (font (size 1.27 1.27) (thickness 0.15)) (justify left))
    )
    (property "License" "Apache-2.0" (at 318.77 131.445 0)
      (effects (font (size 1.27 1.27) (thickness 0.15)) (justify left bottom) hide)
    )
    (property "Author" "Antmicro" (at 316.23 131.445 0)
      (effects (font (size 1.27 1.27) (thickness 0.15)) (justify left bottom) hide)
    )
    (property "Voltage" "" (at 313.69 131.445 0)
      (effects (font (size 1.27 1.27)) (justify left bottom) hide)
    )
    (property "Dielectric" "" (at 311.15 131.445 0)
      (effects (font (size 1.27 1.27)) (justify left bottom) hide)
    )
    (pin "1")
    (pin "2")
    (instances
      (project "data-center-rdimm-ddr4-tester"
        (path ""
          (reference "C250") (unit 1)
        )
      )
    )
  )

  (symbol (lib_id "antmicropower:GND") (at 292.1 116.205 0) (unit 1)
    (in_bom yes) (on_board yes) (dnp no) (fields_autoplaced)
    (property "Reference" "#PWR0313" (at 292.1 122.555 0)
      (effects (font (size 1.27 1.27)) hide)
    )
    (property "Value" "GND" (at 292.1 120.65 0)
      (effects (font (size 1.27 1.27)))
    )
    (property "Footprint" "" (at 292.1 116.205 0)
      (effects (font (size 1.27 1.27)) hide)
    )
    (property "Datasheet" "" (at 292.1 116.205 0)
      (effects (font (size 1.27 1.27)) hide)
    )
    (property "Author" "Antmicro" (at 300.99 123.825 0)
      (effects (font (size 1.27 1.27) (thickness 0.15)) (justify left bottom) hide)
    )
    (property "License" "Apache-2.0" (at 300.99 126.365 0)
      (effects (font (size 1.27 1.27) (thickness 0.15)) (justify left bottom) hide)
    )
    (pin "1")
    (instances
      (project "data-center-rdimm-ddr4-tester"
        (path ""
          (reference "#PWR0313") (unit 1)
        )
      )
    )
  )

  (symbol (lib_id "antmicroCapacitorsmisc:C_100n_0201") (at 64.77 170.18 270) (unit 1)
    (in_bom yes) (on_board yes) (dnp no)
    (property "Reference" "C286" (at 64.77 170.815 90)
      (effects (font (size 1.524 1.524)) (justify left))
    )
    (property "Value" "C_100n_0201" (at 54.61 190.5 0)
      (effects (font (size 1.27 1.27) (thickness 0.15)) (justify left bottom) hide)
    )
    (property "Footprint" "antmicro-footprints:C_0201" (at 52.07 190.5 0)
      (effects (font (size 1.27 1.27) (thickness 0.15)) (justify left bottom) hide)
    )
    (property "Datasheet" " " (at 49.53 190.5 0)
      (effects (font (size 1.27 1.27) (thickness 0.15)) (justify left bottom) hide)
    )
    (property "Manufacturer" "Yaego" (at 44.45 190.5 0)
      (effects (font (size 1.27 1.27) (thickness 0.15)) (justify left bottom) hide)
    )
    (property "MPN" "CC0201KRX6S5BB104" (at 46.99 190.5 0)
      (effects (font (size 1.27 1.27) (thickness 0.15)) (justify left bottom) hide)
    )
    (property "Val" "100n" (at 64.77 174.625 90)
      (effects (font (size 1.27 1.27) (thickness 0.15)) (justify left))
    )
    (property "License" "Apache-2.0" (at 41.91 190.5 0)
      (effects (font (size 1.27 1.27) (thickness 0.15)) (justify left bottom) hide)
    )
    (property "Author" "Antmicro" (at 39.37 190.5 0)
      (effects (font (size 1.27 1.27) (thickness 0.15)) (justify left bottom) hide)
    )
    (property "Voltage" "" (at 36.83 190.5 0)
      (effects (font (size 1.27 1.27)) (justify left bottom) hide)
    )
    (property "Dielectric" "" (at 34.29 190.5 0)
      (effects (font (size 1.27 1.27)) (justify left bottom) hide)
    )
    (pin "1")
    (pin "2")
    (instances
      (project "data-center-rdimm-ddr4-tester"
        (path ""
          (reference "C286") (unit 1)
        )
      )
    )
  )

  (symbol (lib_id "antmicroCapacitorsmisc:C_100n_0201") (at 142.875 201.295 270) (unit 1)
    (in_bom yes) (on_board yes) (dnp no)
    (property "Reference" "C301" (at 142.875 201.93 90)
      (effects (font (size 1.524 1.524)) (justify left))
    )
    (property "Value" "C_100n_0201" (at 132.715 221.615 0)
      (effects (font (size 1.27 1.27) (thickness 0.15)) (justify left bottom) hide)
    )
    (property "Footprint" "antmicro-footprints:C_0201" (at 130.175 221.615 0)
      (effects (font (size 1.27 1.27) (thickness 0.15)) (justify left bottom) hide)
    )
    (property "Datasheet" " " (at 127.635 221.615 0)
      (effects (font (size 1.27 1.27) (thickness 0.15)) (justify left bottom) hide)
    )
    (property "Manufacturer" "Yaego" (at 122.555 221.615 0)
      (effects (font (size 1.27 1.27) (thickness 0.15)) (justify left bottom) hide)
    )
    (property "MPN" "CC0201KRX6S5BB104" (at 125.095 221.615 0)
      (effects (font (size 1.27 1.27) (thickness 0.15)) (justify left bottom) hide)
    )
    (property "Val" "100n" (at 142.875 205.74 90)
      (effects (font (size 1.27 1.27) (thickness 0.15)) (justify left))
    )
    (property "License" "Apache-2.0" (at 120.015 221.615 0)
      (effects (font (size 1.27 1.27) (thickness 0.15)) (justify left bottom) hide)
    )
    (property "Author" "Antmicro" (at 117.475 221.615 0)
      (effects (font (size 1.27 1.27) (thickness 0.15)) (justify left bottom) hide)
    )
    (property "Voltage" "" (at 114.935 221.615 0)
      (effects (font (size 1.27 1.27)) (justify left bottom) hide)
    )
    (property "Dielectric" "" (at 112.395 221.615 0)
      (effects (font (size 1.27 1.27)) (justify left bottom) hide)
    )
    (pin "1")
    (pin "2")
    (instances
      (project "data-center-rdimm-ddr4-tester"
        (path ""
          (reference "C301") (unit 1)
        )
      )
    )
  )

  (symbol (lib_id "antmicropower:GND") (at 64.77 175.26 0) (unit 1)
    (in_bom yes) (on_board yes) (dnp no) (fields_autoplaced)
    (property "Reference" "#PWR0376" (at 64.77 181.61 0)
      (effects (font (size 1.27 1.27)) hide)
    )
    (property "Value" "GND" (at 64.77 180.34 0)
      (effects (font (size 1.27 1.27)))
    )
    (property "Footprint" "" (at 64.77 175.26 0)
      (effects (font (size 1.27 1.27)) hide)
    )
    (property "Datasheet" "" (at 64.77 175.26 0)
      (effects (font (size 1.27 1.27)) hide)
    )
    (property "Author" "Antmicro" (at 73.66 182.88 0)
      (effects (font (size 1.27 1.27) (thickness 0.15)) (justify left bottom) hide)
    )
    (property "License" "Apache-2.0" (at 73.66 185.42 0)
      (effects (font (size 1.27 1.27) (thickness 0.15)) (justify left bottom) hide)
    )
    (pin "1")
    (instances
      (project "data-center-rdimm-ddr4-tester"
        (path ""
          (reference "#PWR0376") (unit 1)
        )
      )
    )
  )

  (symbol (lib_id "antmicropower:GND") (at 277.495 116.205 0) (unit 1)
    (in_bom yes) (on_board yes) (dnp no) (fields_autoplaced)
    (property "Reference" "#PWR0337" (at 277.495 122.555 0)
      (effects (font (size 1.27 1.27)) hide)
    )
    (property "Value" "GND" (at 277.495 120.65 0)
      (effects (font (size 1.27 1.27)))
    )
    (property "Footprint" "" (at 277.495 116.205 0)
      (effects (font (size 1.27 1.27)) hide)
    )
    (property "Datasheet" "" (at 277.495 116.205 0)
      (effects (font (size 1.27 1.27)) hide)
    )
    (property "Author" "Antmicro" (at 286.385 123.825 0)
      (effects (font (size 1.27 1.27) (thickness 0.15)) (justify left bottom) hide)
    )
    (property "License" "Apache-2.0" (at 286.385 126.365 0)
      (effects (font (size 1.27 1.27) (thickness 0.15)) (justify left bottom) hide)
    )
    (pin "1")
    (instances
      (project "data-center-rdimm-ddr4-tester"
        (path ""
          (reference "#PWR0337") (unit 1)
        )
      )
    )
  )

  (symbol (lib_id "antmicroCapacitorsmisc:C_100n_0201") (at 129.54 201.295 270) (unit 1)
    (in_bom yes) (on_board yes) (dnp no)
    (property "Reference" "C299" (at 129.54 201.93 90)
      (effects (font (size 1.524 1.524)) (justify left))
    )
    (property "Value" "C_100n_0201" (at 119.38 221.615 0)
      (effects (font (size 1.27 1.27) (thickness 0.15)) (justify left bottom) hide)
    )
    (property "Footprint" "antmicro-footprints:C_0201" (at 116.84 221.615 0)
      (effects (font (size 1.27 1.27) (thickness 0.15)) (justify left bottom) hide)
    )
    (property "Datasheet" " " (at 114.3 221.615 0)
      (effects (font (size 1.27 1.27) (thickness 0.15)) (justify left bottom) hide)
    )
    (property "Manufacturer" "Yaego" (at 109.22 221.615 0)
      (effects (font (size 1.27 1.27) (thickness 0.15)) (justify left bottom) hide)
    )
    (property "MPN" "CC0201KRX6S5BB104" (at 111.76 221.615 0)
      (effects (font (size 1.27 1.27) (thickness 0.15)) (justify left bottom) hide)
    )
    (property "Val" "100n" (at 129.54 205.74 90)
      (effects (font (size 1.27 1.27) (thickness 0.15)) (justify left))
    )
    (property "License" "Apache-2.0" (at 106.68 221.615 0)
      (effects (font (size 1.27 1.27) (thickness 0.15)) (justify left bottom) hide)
    )
    (property "Author" "Antmicro" (at 104.14 221.615 0)
      (effects (font (size 1.27 1.27) (thickness 0.15)) (justify left bottom) hide)
    )
    (property "Voltage" "" (at 101.6 221.615 0)
      (effects (font (size 1.27 1.27)) (justify left bottom) hide)
    )
    (property "Dielectric" "" (at 99.06 221.615 0)
      (effects (font (size 1.27 1.27)) (justify left bottom) hide)
    )
    (pin "1")
    (pin "2")
    (instances
      (project "data-center-rdimm-ddr4-tester"
        (path ""
          (reference "C299") (unit 1)
        )
      )
    )
  )

  (symbol (lib_id "antmicroCapacitorsmisc:C_100n_0201") (at 108.585 232.41 270) (unit 1)
    (in_bom yes) (on_board yes) (dnp no)
    (property "Reference" "C310" (at 108.585 233.045 90)
      (effects (font (size 1.524 1.524)) (justify left))
    )
    (property "Value" "C_100n_0201" (at 98.425 252.73 0)
      (effects (font (size 1.27 1.27) (thickness 0.15)) (justify left bottom) hide)
    )
    (property "Footprint" "antmicro-footprints:C_0201" (at 95.885 252.73 0)
      (effects (font (size 1.27 1.27) (thickness 0.15)) (justify left bottom) hide)
    )
    (property "Datasheet" " " (at 93.345 252.73 0)
      (effects (font (size 1.27 1.27) (thickness 0.15)) (justify left bottom) hide)
    )
    (property "Manufacturer" "Yaego" (at 88.265 252.73 0)
      (effects (font (size 1.27 1.27) (thickness 0.15)) (justify left bottom) hide)
    )
    (property "MPN" "CC0201KRX6S5BB104" (at 90.805 252.73 0)
      (effects (font (size 1.27 1.27) (thickness 0.15)) (justify left bottom) hide)
    )
    (property "Val" "100n" (at 108.585 236.855 90)
      (effects (font (size 1.27 1.27) (thickness 0.15)) (justify left))
    )
    (property "License" "Apache-2.0" (at 85.725 252.73 0)
      (effects (font (size 1.27 1.27) (thickness 0.15)) (justify left bottom) hide)
    )
    (property "Author" "Antmicro" (at 83.185 252.73 0)
      (effects (font (size 1.27 1.27) (thickness 0.15)) (justify left bottom) hide)
    )
    (property "Voltage" "" (at 80.645 252.73 0)
      (effects (font (size 1.27 1.27)) (justify left bottom) hide)
    )
    (property "Dielectric" "" (at 78.105 252.73 0)
      (effects (font (size 1.27 1.27)) (justify left bottom) hide)
    )
    (pin "1")
    (pin "2")
    (instances
      (project "data-center-rdimm-ddr4-tester"
        (path ""
          (reference "C310") (unit 1)
        )
      )
    )
  )

  (symbol (lib_id "antmicropower:GND") (at 29.21 206.375 0) (unit 1)
    (in_bom yes) (on_board yes) (dnp no) (fields_autoplaced)
    (property "Reference" "#PWR0203" (at 29.21 212.725 0)
      (effects (font (size 1.27 1.27)) hide)
    )
    (property "Value" "GND" (at 29.21 210.82 0)
      (effects (font (size 1.27 1.27)))
    )
    (property "Footprint" "" (at 29.21 206.375 0)
      (effects (font (size 1.27 1.27)) hide)
    )
    (property "Datasheet" "" (at 29.21 206.375 0)
      (effects (font (size 1.27 1.27)) hide)
    )
    (property "Author" "Antmicro" (at 38.1 213.995 0)
      (effects (font (size 1.27 1.27) (thickness 0.15)) (justify left bottom) hide)
    )
    (property "License" "Apache-2.0" (at 38.1 216.535 0)
      (effects (font (size 1.27 1.27) (thickness 0.15)) (justify left bottom) hide)
    )
    (pin "1")
    (instances
      (project "data-center-rdimm-ddr4-tester"
        (path ""
          (reference "#PWR0203") (unit 1)
        )
      )
    )
  )

  (symbol (lib_id "antmicropower:GND") (at 219.71 116.205 0) (unit 1)
    (in_bom yes) (on_board yes) (dnp no) (fields_autoplaced)
    (property "Reference" "#PWR0343" (at 219.71 122.555 0)
      (effects (font (size 1.27 1.27)) hide)
    )
    (property "Value" "GND" (at 219.71 121.793 0)
      (effects (font (size 1.27 1.27)))
    )
    (property "Footprint" "" (at 219.71 116.205 0)
      (effects (font (size 1.27 1.27)) hide)
    )
    (property "Datasheet" "" (at 219.71 116.205 0)
      (effects (font (size 1.27 1.27)) hide)
    )
    (property "Author" "Antmicro" (at 228.6 123.825 0)
      (effects (font (size 1.27 1.27) (thickness 0.15)) (justify left bottom) hide)
    )
    (property "License" "Apache-2.0" (at 228.6 126.365 0)
      (effects (font (size 1.27 1.27) (thickness 0.15)) (justify left bottom) hide)
    )
    (pin "1")
    (instances
      (project "data-center-rdimm-ddr4-tester"
        (path ""
          (reference "#PWR0343") (unit 1)
        )
      )
    )
  )

  (symbol (lib_id "antmicroCapacitorsmisc:C_100n_0201") (at 68.58 232.41 270) (unit 1)
    (in_bom yes) (on_board yes) (dnp no)
    (property "Reference" "C304" (at 68.58 233.045 90)
      (effects (font (size 1.524 1.524)) (justify left))
    )
    (property "Value" "C_100n_0201" (at 58.42 252.73 0)
      (effects (font (size 1.27 1.27) (thickness 0.15)) (justify left bottom) hide)
    )
    (property "Footprint" "antmicro-footprints:C_0201" (at 55.88 252.73 0)
      (effects (font (size 1.27 1.27) (thickness 0.15)) (justify left bottom) hide)
    )
    (property "Datasheet" " " (at 53.34 252.73 0)
      (effects (font (size 1.27 1.27) (thickness 0.15)) (justify left bottom) hide)
    )
    (property "Manufacturer" "Yaego" (at 48.26 252.73 0)
      (effects (font (size 1.27 1.27) (thickness 0.15)) (justify left bottom) hide)
    )
    (property "MPN" "CC0201KRX6S5BB104" (at 50.8 252.73 0)
      (effects (font (size 1.27 1.27) (thickness 0.15)) (justify left bottom) hide)
    )
    (property "Val" "100n" (at 68.58 236.855 90)
      (effects (font (size 1.27 1.27) (thickness 0.15)) (justify left))
    )
    (property "License" "Apache-2.0" (at 45.72 252.73 0)
      (effects (font (size 1.27 1.27) (thickness 0.15)) (justify left bottom) hide)
    )
    (property "Author" "Antmicro" (at 43.18 252.73 0)
      (effects (font (size 1.27 1.27) (thickness 0.15)) (justify left bottom) hide)
    )
    (property "Voltage" "" (at 40.64 252.73 0)
      (effects (font (size 1.27 1.27)) (justify left bottom) hide)
    )
    (property "Dielectric" "" (at 38.1 252.73 0)
      (effects (font (size 1.27 1.27)) (justify left bottom) hide)
    )
    (pin "1")
    (pin "2")
    (instances
      (project "data-center-rdimm-ddr4-tester"
        (path ""
          (reference "C304") (unit 1)
        )
      )
    )
  )

  (symbol (lib_id "antmicroCapacitorsmisc:C_100n_0201") (at 363.855 111.125 270) (unit 1)
    (in_bom yes) (on_board yes) (dnp no)
    (property "Reference" "C254" (at 364.49 111.76 90)
      (effects (font (size 1.524 1.524)) (justify left))
    )
    (property "Value" "C_100n_0201" (at 353.695 131.445 0)
      (effects (font (size 1.27 1.27) (thickness 0.15)) (justify left bottom) hide)
    )
    (property "Footprint" "antmicro-footprints:C_0201" (at 351.155 131.445 0)
      (effects (font (size 1.27 1.27) (thickness 0.15)) (justify left bottom) hide)
    )
    (property "Datasheet" " " (at 348.615 131.445 0)
      (effects (font (size 1.27 1.27) (thickness 0.15)) (justify left bottom) hide)
    )
    (property "Manufacturer" "Yaego" (at 343.535 131.445 0)
      (effects (font (size 1.27 1.27) (thickness 0.15)) (justify left bottom) hide)
    )
    (property "MPN" "CC0201KRX6S5BB104" (at 346.075 131.445 0)
      (effects (font (size 1.27 1.27) (thickness 0.15)) (justify left bottom) hide)
    )
    (property "Val" "100n" (at 364.49 115.57 90)
      (effects (font (size 1.27 1.27) (thickness 0.15)) (justify left))
    )
    (property "License" "Apache-2.0" (at 340.995 131.445 0)
      (effects (font (size 1.27 1.27) (thickness 0.15)) (justify left bottom) hide)
    )
    (property "Author" "Antmicro" (at 338.455 131.445 0)
      (effects (font (size 1.27 1.27) (thickness 0.15)) (justify left bottom) hide)
    )
    (property "Voltage" "" (at 335.915 131.445 0)
      (effects (font (size 1.27 1.27)) (justify left bottom) hide)
    )
    (property "Dielectric" "" (at 333.375 131.445 0)
      (effects (font (size 1.27 1.27)) (justify left bottom) hide)
    )
    (pin "1")
    (pin "2")
    (instances
      (project "data-center-rdimm-ddr4-tester"
        (path ""
          (reference "C254") (unit 1)
        )
      )
    )
  )

  (symbol (lib_id "antmicroCapacitorsmisc:C_100n_0201") (at 62.865 201.295 270) (unit 1)
    (in_bom yes) (on_board yes) (dnp no)
    (property "Reference" "C87" (at 62.865 201.93 90)
      (effects (font (size 1.524 1.524)) (justify left))
    )
    (property "Value" "C_100n_0201" (at 52.705 221.615 0)
      (effects (font (size 1.27 1.27) (thickness 0.15)) (justify left bottom) hide)
    )
    (property "Footprint" "antmicro-footprints:C_0201" (at 50.165 221.615 0)
      (effects (font (size 1.27 1.27) (thickness 0.15)) (justify left bottom) hide)
    )
    (property "Datasheet" " " (at 47.625 221.615 0)
      (effects (font (size 1.27 1.27) (thickness 0.15)) (justify left bottom) hide)
    )
    (property "Manufacturer" "Yaego" (at 42.545 221.615 0)
      (effects (font (size 1.27 1.27) (thickness 0.15)) (justify left bottom) hide)
    )
    (property "MPN" "CC0201KRX6S5BB104" (at 45.085 221.615 0)
      (effects (font (size 1.27 1.27) (thickness 0.15)) (justify left bottom) hide)
    )
    (property "Val" "100n" (at 62.865 205.74 90)
      (effects (font (size 1.27 1.27) (thickness 0.15)) (justify left))
    )
    (property "License" "Apache-2.0" (at 40.005 221.615 0)
      (effects (font (size 1.27 1.27) (thickness 0.15)) (justify left bottom) hide)
    )
    (property "Author" "Antmicro" (at 37.465 221.615 0)
      (effects (font (size 1.27 1.27) (thickness 0.15)) (justify left bottom) hide)
    )
    (property "Voltage" "" (at 34.925 221.615 0)
      (effects (font (size 1.27 1.27)) (justify left bottom) hide)
    )
    (property "Dielectric" "" (at 32.385 221.615 0)
      (effects (font (size 1.27 1.27)) (justify left bottom) hide)
    )
    (pin "1")
    (pin "2")
    (instances
      (project "data-center-rdimm-ddr4-tester"
        (path ""
          (reference "C87") (unit 1)
        )
      )
    )
  )

  (symbol (lib_id "antmicroCapacitorsmisc:C_100n_0201") (at 102.235 232.41 270) (unit 1)
    (in_bom yes) (on_board yes) (dnp no)
    (property "Reference" "C309" (at 102.235 233.045 90)
      (effects (font (size 1.524 1.524)) (justify left))
    )
    (property "Value" "C_100n_0201" (at 92.075 252.73 0)
      (effects (font (size 1.27 1.27) (thickness 0.15)) (justify left bottom) hide)
    )
    (property "Footprint" "antmicro-footprints:C_0201" (at 89.535 252.73 0)
      (effects (font (size 1.27 1.27) (thickness 0.15)) (justify left bottom) hide)
    )
    (property "Datasheet" " " (at 86.995 252.73 0)
      (effects (font (size 1.27 1.27) (thickness 0.15)) (justify left bottom) hide)
    )
    (property "Manufacturer" "Yaego" (at 81.915 252.73 0)
      (effects (font (size 1.27 1.27) (thickness 0.15)) (justify left bottom) hide)
    )
    (property "MPN" "CC0201KRX6S5BB104" (at 84.455 252.73 0)
      (effects (font (size 1.27 1.27) (thickness 0.15)) (justify left bottom) hide)
    )
    (property "Val" "100n" (at 102.235 236.855 90)
      (effects (font (size 1.27 1.27) (thickness 0.15)) (justify left))
    )
    (property "License" "Apache-2.0" (at 79.375 252.73 0)
      (effects (font (size 1.27 1.27) (thickness 0.15)) (justify left bottom) hide)
    )
    (property "Author" "Antmicro" (at 76.835 252.73 0)
      (effects (font (size 1.27 1.27) (thickness 0.15)) (justify left bottom) hide)
    )
    (property "Voltage" "" (at 74.295 252.73 0)
      (effects (font (size 1.27 1.27)) (justify left bottom) hide)
    )
    (property "Dielectric" "" (at 71.755 252.73 0)
      (effects (font (size 1.27 1.27)) (justify left bottom) hide)
    )
    (pin "1")
    (pin "2")
    (instances
      (project "data-center-rdimm-ddr4-tester"
        (path ""
          (reference "C309") (unit 1)
        )
      )
    )
  )

  (symbol (lib_id "antmicropower:GND") (at 363.855 116.205 0) (unit 1)
    (in_bom yes) (on_board yes) (dnp no) (fields_autoplaced)
    (property "Reference" "#PWR0150" (at 363.855 122.555 0)
      (effects (font (size 1.27 1.27)) hide)
    )
    (property "Value" "GND" (at 363.855 120.65 0)
      (effects (font (size 1.27 1.27)))
    )
    (property "Footprint" "" (at 363.855 116.205 0)
      (effects (font (size 1.27 1.27)) hide)
    )
    (property "Datasheet" "" (at 363.855 116.205 0)
      (effects (font (size 1.27 1.27)) hide)
    )
    (property "Author" "Antmicro" (at 372.745 123.825 0)
      (effects (font (size 1.27 1.27) (thickness 0.15)) (justify left bottom) hide)
    )
    (property "License" "Apache-2.0" (at 372.745 126.365 0)
      (effects (font (size 1.27 1.27) (thickness 0.15)) (justify left bottom) hide)
    )
    (pin "1")
    (instances
      (project "data-center-rdimm-ddr4-tester"
        (path ""
          (reference "#PWR0150") (unit 1)
        )
      )
    )
  )

  (symbol (lib_id "antmicroCapacitorsmisc:C_100n_0201") (at 28.575 232.41 270) (unit 1)
    (in_bom yes) (on_board yes) (dnp no)
    (property "Reference" "C82" (at 28.575 233.045 90)
      (effects (font (size 1.524 1.524)) (justify left))
    )
    (property "Value" "C_100n_0201" (at 18.415 252.73 0)
      (effects (font (size 1.27 1.27) (thickness 0.15)) (justify left bottom) hide)
    )
    (property "Footprint" "antmicro-footprints:C_0201" (at 15.875 252.73 0)
      (effects (font (size 1.27 1.27) (thickness 0.15)) (justify left bottom) hide)
    )
    (property "Datasheet" " " (at 13.335 252.73 0)
      (effects (font (size 1.27 1.27) (thickness 0.15)) (justify left bottom) hide)
    )
    (property "Manufacturer" "Yaego" (at 8.255 252.73 0)
      (effects (font (size 1.27 1.27) (thickness 0.15)) (justify left bottom) hide)
    )
    (property "MPN" "CC0201KRX6S5BB104" (at 10.795 252.73 0)
      (effects (font (size 1.27 1.27) (thickness 0.15)) (justify left bottom) hide)
    )
    (property "Val" "100n" (at 28.575 236.855 90)
      (effects (font (size 1.27 1.27) (thickness 0.15)) (justify left))
    )
    (property "License" "Apache-2.0" (at 5.715 252.73 0)
      (effects (font (size 1.27 1.27) (thickness 0.15)) (justify left bottom) hide)
    )
    (property "Author" "Antmicro" (at 3.175 252.73 0)
      (effects (font (size 1.27 1.27) (thickness 0.15)) (justify left bottom) hide)
    )
    (property "Voltage" "" (at 0.635 252.73 0)
      (effects (font (size 1.27 1.27)) (justify left bottom) hide)
    )
    (property "Dielectric" "" (at -1.905 252.73 0)
      (effects (font (size 1.27 1.27)) (justify left bottom) hide)
    )
    (pin "1")
    (pin "2")
    (instances
      (project "data-center-rdimm-ddr4-tester"
        (path ""
          (reference "C82") (unit 1)
        )
      )
    )
  )

  (symbol (lib_id "antmicroCapacitors0402:C_4u7_0402") (at 229.87 111.125 270) (unit 1)
    (in_bom yes) (on_board yes) (dnp no) (fields_autoplaced)
    (property "Reference" "C239" (at 232.41 112.4013 90)
      (effects (font (size 1.524 1.524)) (justify left))
    )
    (property "Value" "C_4u7_0402" (at 219.71 131.445 0)
      (effects (font (size 1.27 1.27) (thickness 0.15)) (justify left bottom) hide)
    )
    (property "Footprint" "antmicro-footprints:C_0402_1005Metric" (at 217.17 131.445 0)
      (effects (font (size 1.27 1.27) (thickness 0.15)) (justify left bottom) hide)
    )
    (property "Datasheet" " " (at 214.63 131.445 0)
      (effects (font (size 1.27 1.27) (thickness 0.15)) (justify left bottom) hide)
    )
    (property "Manufacturer" "Murata" (at 209.55 131.445 0)
      (effects (font (size 1.27 1.27) (thickness 0.15)) (justify left bottom) hide)
    )
    (property "MPN" "GRM155R61A475MEAAD" (at 212.09 131.445 0)
      (effects (font (size 1.27 1.27) (thickness 0.15)) (justify left bottom) hide)
    )
    (property "Val" "4u7" (at 232.41 115.5762 90)
      (effects (font (size 1.27 1.27) (thickness 0.15)) (justify left))
    )
    (property "License" "Apache-2.0" (at 207.01 131.445 0)
      (effects (font (size 1.27 1.27) (thickness 0.15)) (justify left bottom) hide)
    )
    (property "Author" "Antmicro" (at 204.47 131.445 0)
      (effects (font (size 1.27 1.27) (thickness 0.15)) (justify left bottom) hide)
    )
    (property "Voltage" "" (at 201.93 131.445 0)
      (effects (font (size 1.27 1.27)) (justify left bottom) hide)
    )
    (property "Dielectric" "" (at 199.39 131.445 0)
      (effects (font (size 1.27 1.27)) (justify left bottom) hide)
    )
    (pin "1")
    (pin "2")
    (instances
      (project "data-center-rdimm-ddr4-tester"
        (path ""
          (reference "C239") (unit 1)
        )
      )
    )
  )
)
